G04 ================== begin FILE IDENTIFICATION RECORD ==================*
G04 Layout Name:  9048_F0T_Management_Board_D_brd_V04_1213_1625.brd*
G04 Film Name:    in3*
G04 File Format:  Gerber RS274X*
G04 File Origin:  Cadence Allegro 17.2-S081*
G04 Origin Date:  Tue Dec 13 16:31:11 2022*
G04 *
G04 Layer:  DRAWING FORMAT/TITLE_BLOCK_A*
G04 Layer:  VIA CLASS/IN3*
G04 Layer:  PIN/IN3*
G04 Layer:  MANUFACTURING/PHOTOPLOT_OUTLINE*
G04 Layer:  ETCH/IN3*
G04 Layer:  DRAWING FORMAT/TITLE_BLOCK*
G04 Layer:  DRAWING FORMAT/TITLE_DATA_IN3*
G04 *
G04 Offset:    (0.00 0.00)*
G04 Mirror:    No*
G04 Mode:      Positive*
G04 Rotation:  0*
G04 FullContactRelief:  No*
G04 UndefLineWidth:     6.00*
G04 ================== end FILE IDENTIFICATION RECORD ====================*
%FSLAX25Y25*MOIN*%
%IR0*IPPOS*OFA0.00000B0.00000*MIA0B0*SFA1.00000B1.00000*%
%ADD11C,.02*%
%ADD12C,.018*%
%ADD10C,.085*%
%ADD13C,.01*%
%ADD14C,.006*%
%ADD15C,.0042*%
%ADD16C,.03004*%
%ADD17C,.02604*%
%ADD18C,.02804*%
G75*
%LPD*%
G75*
G36*
G01X331081Y468024D02*
X332262D01*
X332646Y467640D01*
Y451968D01*
G03X336614Y448000I3969J1D01*
G01X346457D01*
G02X352331Y442126I0J-5874D01*
G01Y336646D01*
X345472D01*
G03X341504Y332678I0J-3968D01*
G01Y322834D01*
G03X345472Y318866I3968J0D01*
G01X352331D01*
Y7874D01*
G02X346457Y2000I-5874J0D01*
G01X7874D01*
G02X2000Y7874I0J5874D01*
G01Y318866D01*
X8858D01*
G03X12827Y322835I0J3969D01*
G01Y332677D01*
G03X8858Y336646I-3969J0D01*
G01X2000D01*
Y442126D01*
G02X7874Y448000I5874J0D01*
G01X17717D01*
G03X21685Y451968I-1J3969D01*
G01Y467365D01*
X22132Y467812D01*
X23372D01*
X23682Y467502D01*
Y451968D01*
G02X17717Y446002I-5966J0D01*
G01X7874D01*
G03X3998Y442126I0J-3876D01*
G01Y338644D01*
X8858D01*
G02X12985Y336986I-1J-5967D01*
G01X13166Y336805D01*
G02X14326Y335062I-4310J-4126D01*
G01X14411Y334858D01*
G02X14822Y332811I-5554J-2180D01*
G01Y322700D01*
G02X8858Y316868I-5964J133D01*
G01X3998D01*
Y306886D01*
G03X3996Y306830I1209J-71D01*
G01Y36692D01*
G03X3998Y36636I1211J15D01*
G01Y7874D01*
G03X7874Y3998I3876J0D01*
G01X250898D01*
X301602D01*
X346457D01*
G03X350334Y7874I0J3877D01*
G01Y316868D01*
X347898D01*
G03X347842Y316870I-71J-1209D01*
G01X345339D01*
G02X341326Y318544I133J5965D01*
G01X341182Y318688D01*
G02X339506Y322834I4291J4146D01*
G01Y332678D01*
G02X345472Y338644I5966J-1D01*
G01X350334D01*
Y442126D01*
G03X346459Y446002I-3876J0D01*
G01X336614D01*
G02X330648Y451968I0J5966D01*
G01Y467591D01*
X331081Y468024D01*
G37*
G36*
G01X32601Y315972D02*
X34565D01*
G03X34618Y315970I68J1109D01*
G01X38428D01*
X41900Y312498D01*
Y299689D01*
X47965Y293624D01*
Y278515D01*
G02X47282Y278232I-400J0D01*
G03X46220Y278672I-1062J-1062D01*
G03X44718Y277170I0J-1502D01*
G03X44798Y276687I1502J1D01*
G01X44808Y276655D01*
Y264577D01*
G03X44548Y263759I1152J-816D01*
G01Y232848D01*
X37800Y226100D01*
Y219436D01*
X42236Y215000D01*
Y199105D01*
X49188Y192152D01*
Y179100D01*
G03X49602Y178102I1412J1D01*
G01X52636Y175068D01*
Y131424D01*
G02X52236Y131024I-400J0D01*
G03X51350Y130734I1J-1502D01*
G02X50719Y130994I-236J323D01*
G03X49236Y132260I-1483J-236D01*
G03X47734Y130758I0J-1502D01*
G03X48313Y129573I1502J0D01*
G02Y128943I-246J-315D01*
G03X47734Y127758I923J-1185D01*
G03X50738I1502J0D01*
G03X50159Y128943I-1502J0D01*
G02Y129573I246J315D01*
G03X50388Y129794I-923J1185D01*
G02X50740Y129649I153J-129D01*
G03X50735Y129522I1497J-123D01*
G03X52236Y128020I1502J0D01*
G02X52636Y127620I0J-400D01*
G01Y114766D01*
X51979Y114109D01*
X29465D01*
X26466Y117108D01*
G03X26008Y117566I-1266J-808D01*
G01X15221Y128353D01*
Y220900D01*
X16621Y222300D01*
X22300D01*
X23000Y223000D01*
Y228100D01*
X21700Y229400D01*
X16221D01*
X15221Y230400D01*
Y254474D01*
G02X15925Y254734I400J0D01*
G03X17065Y254210I1140J978D01*
G03Y257214I0J1502D01*
G03X15925Y256690I0J-1502D01*
G02X15221Y256950I-304J260D01*
G01Y299665D01*
X15223Y299679D01*
G03X15238Y299891I-1487J212D01*
G03X15223Y300103I-1502J0D01*
G01X15221Y300117D01*
Y303054D01*
X15223Y303068D01*
G03X15238Y303280I-1487J212D01*
G03X15223Y303492I-1502J0D01*
G01X15221Y303506D01*
Y308508D01*
X22685Y315972D01*
X28799D01*
G02X29199Y315557I0J-400D01*
G03X29198Y315500I1501J-55D01*
G03X32202I1502J0D01*
G03X32201Y315557I-1502J2D01*
G02X32601Y315972I400J15D01*
G37*
G36*
G01X38828Y468024D02*
X40009D01*
X40382Y467651D01*
Y451968D01*
G03X44350Y448000I3969J1D01*
G01X45976D01*
X46336Y447640D01*
Y446364D01*
X45974Y446002D01*
X44350D01*
G02X38384Y451968I0J5966D01*
G01Y467580D01*
X38828Y468024D01*
G37*
G36*
G01X91922Y397100D02*
X108200D01*
X110000Y395300D01*
Y392600D01*
X108200Y390800D01*
Y390513D01*
X107663Y389977D01*
G03X107308Y389120I857J-857D01*
G01Y372114D01*
X107294Y372077D01*
G03X107128Y371239I2045J-841D01*
G01Y364910D01*
G03X107294Y364072I2211J3D01*
G01X107308Y364035D01*
Y357780D01*
G03X107663Y356923I1212J0D01*
G01X108388Y356198D01*
Y354658D01*
X108380Y354630D01*
G03X108288Y354000I2120J-631D01*
G01Y346844D01*
X100760Y339315D01*
G02X100172Y339339I-283J283D01*
G03X99026Y339870I-1146J-971D01*
G03X97524Y338368I0J-1502D01*
G03X97652Y337761I1503J0D01*
G02X97286Y337200I-366J-161D01*
G01X83408D01*
X83378Y337365D01*
G03X81900Y338602I-1478J-264D01*
G03X80567Y337792I0J-1502D01*
G02X79936Y337687I-355J185D01*
G03X78900Y338102I-1036J-1086D01*
G03X77574Y337306I0J-1502D01*
G01X77518Y337200D01*
X68600D01*
X63419Y342381D01*
X63518Y342519D01*
G03X63760Y343275I-1060J756D01*
G03X62458Y344577I-1302J0D01*
G03X61702Y344335I0J-1302D01*
G01X61564Y344236D01*
X60700Y345100D01*
Y347000D01*
X61400Y347700D01*
X66600D01*
X67504Y346796D01*
X67482Y346690D01*
G03X67455Y346425I1275J-264D01*
G03X68757Y345123I1302J0D01*
G03X68858Y345127I-1J1302D01*
G01X68950Y345134D01*
X70185Y343898D01*
X80138D01*
G02X80485Y343299I0J-400D01*
G03X80298Y342600I1215J-700D01*
G03X83102I1402J0D01*
G03X82915Y343299I-1402J-1D01*
G02X83262Y343898I347J199D01*
G01X98315D01*
X98616Y344200D01*
X99300D01*
X100184Y345084D01*
X100266Y345085D01*
G03X101555Y346374I-13J1302D01*
G01X101556Y346456D01*
X101864Y346764D01*
X102067Y346561D01*
X102064Y346474D01*
G03X102063Y346425I1301J-51D01*
G03X103365Y347727I1302J0D01*
G03X102474Y347374I0J-1301D01*
G02X101800Y347666I-274J292D01*
G01Y348332D01*
G02X102478Y348620I400J0D01*
G03X103383Y348254I905J936D01*
G03Y350858I0J1302D01*
G03X102478Y350492I0J-1302D01*
G02X101800Y350780I-278J288D01*
G01Y354100D01*
X101047Y354853D01*
X101176Y354994D01*
G03X101517Y355873I-962J879D01*
G03X100215Y357175I-1302J0D01*
G03X99336Y356834I0J-1303D01*
G01X99195Y356705D01*
X96400Y359500D01*
X95134D01*
X95078Y359610D01*
G03X92754I-1162J-587D01*
G01X92698Y359500D01*
X91984D01*
X91928Y359610D01*
G03X90766Y360325I-1162J-587D01*
G03X90451Y360286I1J-1302D01*
G01X90341Y360259D01*
X89602Y360999D01*
Y363715D01*
X88713Y364604D01*
X88778Y364733D01*
G03X88919Y365322I-1160J589D01*
G03X86315I-1302J0D01*
G03X86476Y364696I1302J1D01*
G01X86548Y364564D01*
X81998Y360015D01*
Y359899D01*
X81600Y359500D01*
X79424D01*
X79368Y359610D01*
G03X78206Y360325I-1162J-587D01*
G03X77299Y359958I-1J-1302D01*
G02X76738Y359962I-278J287D01*
G01X76300Y360400D01*
Y361788D01*
X76308Y361815D01*
G03X76358Y362175I-1252J357D01*
G01Y362258D01*
X77299Y363198D01*
X78815D01*
X79946Y364329D01*
G02X80493Y364346I283J-283D01*
G03X81355Y364020I862J977D01*
G03Y366624I0J1302D01*
G03X80702Y366448I1J-1302D01*
G02X80102Y366794I-200J346D01*
G01Y370112D01*
G02X80702Y370458I400J0D01*
G03X81355Y370282I654J1126D01*
G03Y372886I0J1302D01*
G03X80491Y372558I0J-1302D01*
G02X79942Y372574I-266J299D01*
G01X78815Y373702D01*
X77300D01*
Y376000D01*
X77911Y376611D01*
X78011Y376596D01*
G03X78206Y376581I197J1287D01*
G03X78714Y376684I0J1302D01*
G01X78751Y376700D01*
X80810D01*
X80847Y376684D01*
G03X81355Y376581I508J1199D01*
G03X81786Y376654I1J1302D01*
G01X81904Y376696D01*
X82998Y375601D01*
Y375285D01*
X85785Y372498D01*
X85995D01*
G02X86376Y371978I0J-400D01*
G03X86315Y371584I1242J-394D01*
G03X88919I1302J0D01*
G03X88750Y372226I-1302J0D01*
G01X88675Y372358D01*
X90502Y374185D01*
Y375285D01*
X92311Y377094D01*
G02X92904Y377063I283J-283D01*
G03X93916Y376581I1012J821D01*
G03X95218Y377883I0J1302D01*
G03X94736Y378895I-1303J0D01*
G02X94705Y379488I252J310D01*
G01X95461Y380244D01*
G02X96054Y380213I283J-283D01*
G03X97066Y379731I1012J821D01*
G03X98368Y381033I0J1302D01*
G03X98305Y381434I-1302J1D01*
G01X98267Y381551D01*
X99102Y382385D01*
Y382637D01*
G02X99669Y383000I400J0D01*
G03X100215Y382880I546J1182D01*
G03Y385484I0J1302D01*
G03X99423Y385216I-1J-1302D01*
G02X99102Y385374I-121J159D01*
G01Y385415D01*
X99000Y385516D01*
Y385600D01*
X98089Y386511D01*
X98172Y386646D01*
G03X98368Y387332I-1106J687D01*
G03X97066Y388634I-1302J0D01*
G03X95785Y387564I0J-1302D01*
G01X95755Y387400D01*
X95227D01*
X95197Y387564D01*
G03X92635I-1281J-232D01*
G01X92605Y387400D01*
X92077D01*
X92047Y387564D01*
G03X89485I-1281J-232D01*
G01X89455Y387400D01*
X88928D01*
X88898Y387564D01*
G03X86336I-1281J-232D01*
G01X86306Y387400D01*
X82666D01*
X82636Y387564D01*
G03X80074I-1281J-232D01*
G01X80044Y387400D01*
X76800D01*
X74802Y389399D01*
Y389615D01*
X73215Y391202D01*
X63542D01*
G03X62458Y391783I-1084J-721D01*
G03X61156Y390481I0J-1302D01*
G03X61157Y390419I1302J-10D01*
G02X60758Y390000I-399J-19D01*
G01X60152D01*
Y391997D01*
G03X59738Y392995I-1412J-1D01*
G01X58112Y394622D01*
Y396011D01*
X59200Y397100D01*
X77656D01*
G02X77954Y396434I0J-400D01*
G03X77598Y395500I1047J-934D01*
G03X80402I1402J0D01*
G03X80046Y396434I-1403J0D01*
G02X80344Y397100I298J266D01*
G01X81078D01*
X81131Y396982D01*
G03X83869I1369J618D01*
G01X83922Y397100D01*
X84878D01*
X84931Y396982D01*
G03X87669I1369J618D01*
G01X87722Y397100D01*
X89078D01*
X89131Y396982D01*
G03X91869I1369J618D01*
G01X91922Y397100D01*
G37*
G36*
G01X64200Y390200D02*
X72800D01*
X73800Y389200D01*
Y387800D01*
X72400Y386400D01*
X71200D01*
X69794Y384994D01*
X69652Y385127D01*
G03X68757Y385484I-896J-945D01*
G03Y382880I0J-1302D01*
G03X69713Y383299I-1J1302D01*
G02X70290Y383310I294J-272D01*
G01X72700Y380900D01*
Y379539D01*
G02X72207Y379150I-400J0D01*
G03X71906Y379185I-300J-1267D01*
G03Y376581I0J-1302D01*
G03X72207Y376616I1J1302D01*
G02X72700Y376227I93J-389D01*
G01Y375913D01*
X72459D01*
X72421Y375929D01*
G03X71906Y376035I-515J-1196D01*
G03Y373431I0J-1302D01*
G03X72996Y374022I0J1301D01*
G02X73614Y374086I335J-219D01*
G01X75000Y372700D01*
X78400D01*
X79100Y372000D01*
Y364900D01*
X78400Y364200D01*
X76597D01*
G02X76235Y364770I0J400D01*
G03X76358Y365322I-1179J552D01*
G03X73754I-1302J0D01*
G03X73877Y364770I1302J0D01*
G02X73515Y364200I-362J-170D01*
G01X73447D01*
G02X73085Y364770I0J400D01*
G03X73208Y365322I-1179J552D01*
G03X70604I-1302J0D01*
G03X71767Y364027I1302J0D01*
G01X71837Y364020D01*
X72029Y363829D01*
X71651Y363451D01*
X71597Y363438D01*
G03X70604Y362173I309J-1265D01*
G03X70900Y361346I1303J0D01*
G01Y359850D01*
G03Y358196I1007J-827D01*
G01Y356700D01*
G03X70604Y355873I1007J-827D01*
G03X70613Y355721I1302J1D01*
G01X70624Y355624D01*
X70000Y355000D01*
X67242D01*
G02X66858Y355511I0J400D01*
G03X66909Y355873I-1251J361D01*
G03X64305I-1302J0D01*
G03X64371Y355465I1302J1D01*
G01X64409Y355348D01*
X64181Y355119D01*
X63729Y355571D01*
X63744Y355672D01*
G03X63760Y355873I-1286J203D01*
G03X63300Y356866I-1302J0D01*
G01Y378900D01*
X61900Y380300D01*
Y387900D01*
X64200Y390200D01*
G37*
G36*
G01X70500Y157000D02*
X77500D01*
X87500Y147000D01*
Y135788D01*
X87486Y135752D01*
G03X87354Y135057I1770J-696D01*
G01Y131643D01*
G03X87486Y130948I1902J1D01*
G01X87500Y130912D01*
Y130500D01*
X91629Y126371D01*
Y121100D01*
X90600Y120071D01*
Y118768D01*
G03X90598Y118700I1899J-90D01*
G01Y116200D01*
G03X90600Y116132I1901J22D01*
G01Y115200D01*
X92000Y113800D01*
X93500D01*
X94300Y113000D01*
Y84500D01*
X92656D01*
G03X92281Y84930I-1299J-754D01*
G02Y85560I246J315D01*
G03Y87930I-923J1185D01*
G02Y88560I246J315D01*
G03Y90930I-923J1185D01*
G02Y91560I246J315D01*
G03X92860Y92745I-923J1185D01*
G03X89856I-1502J0D01*
G03X90435Y91560I1502J0D01*
G02Y90930I-246J-315D01*
G03Y88560I923J-1185D01*
G02Y87930I-246J-315D01*
G03Y85560I923J-1185D01*
G02Y84930I-246J-315D01*
G03X90060Y84500I924J-1184D01*
G01X76055D01*
G03X75680Y84930I-1299J-754D01*
G02Y85560I246J315D01*
G03Y87930I-923J1185D01*
G02Y88560I246J315D01*
G03Y90930I-923J1185D01*
G02Y91560I246J315D01*
G03X76259Y92745I-923J1185D01*
G03X73255I-1502J0D01*
G03X73834Y91560I1502J0D01*
G02Y90930I-246J-315D01*
G03Y88560I923J-1185D01*
G02X73839Y87934I-246J-315D01*
G03X73255Y86745I918J-1189D01*
G03X73263Y86588I1502J-2D01*
G01X73265Y86569D01*
G03X73834Y85560I1492J176D01*
G02Y84930I-246J-315D01*
G03X73459Y84500I924J-1184D01*
G01X70036D01*
X64860Y89676D01*
Y109539D01*
X65485Y111362D01*
X65507Y111390D01*
G03X65774Y112146I-945J759D01*
G01Y112204D01*
X68626Y120527D01*
Y128032D01*
G03X68628Y128100I-1500J78D01*
G03X68626Y128168I-1502J-10D01*
G01Y139474D01*
X68275Y139825D01*
X68272Y139828D01*
G03X68265Y139835I-860J-852D01*
G03X68242Y139860I-903J-808D01*
G01X67612Y140489D01*
X67316Y140785D01*
Y153816D01*
X70500Y157000D01*
G37*
G36*
G01X89077Y313045D02*
X76945D01*
X74516Y310616D01*
Y297561D01*
X75182Y296895D01*
X87895D01*
X89385Y298385D01*
Y312737D01*
X89077Y313045D01*
G37*
G36*
G01X87100Y363700D02*
X88200D01*
X88600Y363300D01*
Y361300D01*
X88300Y361000D01*
Y360701D01*
G02X87834Y360307I-400J0D01*
G03X87617Y360325I-216J-1284D01*
G03Y357721I0J-1302D01*
G03X87834Y357739I1J1302D01*
G02X88300Y357345I66J-394D01*
G01Y357095D01*
X88067D01*
X88036Y357106D01*
G03X87617Y357175I-418J-1233D01*
G03Y354571I0J-1302D01*
G03X88825Y355387I0J1302D01*
G02X89479Y355521I371J-149D01*
G01X89526Y355474D01*
X89541Y355432D01*
G03X90766Y354571I1225J441D01*
G03X91631Y354900I0J1302D01*
G01X93051D01*
G03X94781I865J973D01*
G01X96201D01*
G03X97066Y354571I865J973D01*
G03X97732Y354754I0J1303D01*
G01X97866Y354834D01*
X98900Y353800D01*
Y345900D01*
X97900Y344900D01*
X82632D01*
G02X82332Y345564I0J400D01*
G03X82657Y346425I-978J861D01*
G03X80053I-1302J0D01*
G03X80378Y345564I1303J0D01*
G02X80078Y344900I-300J-264D01*
G01X76333D01*
G02X76033Y345564I0J400D01*
G03X76358Y346425I-978J861D01*
G03X73754I-1302J0D01*
G03X74079Y345564I1303J0D01*
G02X73779Y344900I-300J-264D01*
G01X70600D01*
X69900Y345600D01*
Y345800D01*
X69921Y345842D01*
G03X70059Y346425I-1164J583D01*
G03X69921Y347008I-1302J0D01*
G01X69900Y347050D01*
Y348949D01*
X69921Y348991D01*
G03X70059Y349574I-1164J583D01*
G03X69921Y350157I-1302J0D01*
G01X69900Y350199D01*
Y352099D01*
X69921Y352141D01*
G03X70037Y352488I-1164J582D01*
G01X70049Y352549D01*
X71200Y353700D01*
X73454D01*
G02X73831Y353165I0J-400D01*
G03X73754Y352724I1224J-441D01*
G03X76358I1302J0D01*
G03X76281Y353165I-1301J0D01*
G02X76658Y353700I377J135D01*
G01X80700D01*
X81591Y354591D01*
X81647Y354604D01*
G03X82624Y355581I-292J1269D01*
G01X82637Y355637D01*
X83000Y356000D01*
Y359600D01*
X87100Y363700D01*
G37*
G36*
G01X73316Y385900D02*
X97200D01*
X98100Y385000D01*
Y382800D01*
X97548Y382248D01*
X97434Y382282D01*
G03X97066Y382335I-368J-1249D01*
G03X96527Y382218I0J-1302D01*
G01X96487Y382200D01*
X96000D01*
X95565Y381765D01*
G02X94961Y381809I-283J283D01*
G03X93916Y382335I-1045J-775D01*
G03X92614Y381033I0J-1302D01*
G03X93140Y379988I1301J0D01*
G02X93184Y379384I-239J-321D01*
G01X92415Y378615D01*
G02X91811Y378659I-283J283D01*
G03X90766Y379185I-1045J-775D01*
G03X89464Y377883I0J-1302D01*
G03X89990Y376838I1301J0D01*
G02X90034Y376234I-239J-321D01*
G01X89500Y375700D01*
Y375038D01*
X89495Y375016D01*
G03X89464Y374733I1271J-282D01*
G03X89466Y374660I1302J-1D01*
G01X89471Y374571D01*
X88400Y373500D01*
X86200D01*
X84000Y375700D01*
Y376700D01*
X82647Y378053D01*
X82636Y378114D01*
G03X81355Y379185I-1281J-231D01*
G03X80268Y378600I0J-1302D01*
G01X79293D01*
G03X77119I-1087J-717D01*
G01X76143D01*
G03X75056Y379185I-1087J-717D01*
G03X74326Y378961I0J-1302D01*
G02X73702Y379292I-224J331D01*
G01Y379599D01*
G02X74317Y379936I400J0D01*
G03X75018Y379731I701J1096D01*
G03Y382335I0J1302D01*
G03X73936Y381757I0J-1302D01*
G02X73320Y381696I-333J222D01*
G01X71002Y384015D01*
Y384785D01*
X71615Y385398D01*
X72815D01*
X73316Y385900D01*
G37*
G36*
G01X142142Y225347D02*
X147093D01*
X147505Y224935D01*
Y216671D01*
X146664Y215830D01*
G03X146365Y215286I786J-786D01*
G01X146330Y215130D01*
X141652D01*
X141062Y215720D01*
Y223287D01*
G03X141060Y223340I-1111J-15D01*
G01Y224265D01*
X142142Y225347D01*
G37*
G36*
G01X160402Y235400D02*
X163200D01*
X164300Y234300D01*
Y231043D01*
G02X163816Y230652I-400J0D01*
G03X163500Y230686I-318J-1468D01*
G03Y227682I0J-1502D01*
G03X163816Y227716I-2J1502D01*
G02X164300Y227325I84J-391D01*
G01Y218100D01*
X163600Y217400D01*
X161000D01*
X160872Y217528D01*
Y218235D01*
G03X160779Y218699I-1204J0D01*
G01X159713Y221272D01*
G03X159451Y221665I-1120J-463D01*
G01X158844Y222271D01*
Y231274D01*
X160047Y232476D01*
G03X160402Y233333I-857J857D01*
G01Y235400D01*
G37*
G36*
G01X173135Y256988D02*
X178163D01*
X178856Y256295D01*
X178729Y256154D01*
G03X178344Y255150I1117J-1004D01*
G03X179846Y253648I1502J0D01*
G03X181302Y254782I0J1502D01*
G02X181973Y254966I388J-98D01*
G01X182211Y254728D01*
Y254704D01*
X183291Y253624D01*
Y217809D01*
X186891Y214209D01*
X186779Y214069D01*
G03X186492Y213254I1014J-815D01*
G03X187794Y211952I1302J0D01*
G03X188609Y212239I0J1301D01*
G01X188749Y212351D01*
X189930Y211170D01*
X191290D01*
X191770Y210690D01*
Y206420D01*
X191098Y205748D01*
X188703D01*
X187423Y204468D01*
X185766D01*
G03X183524I-1121J-664D01*
G01X182616D01*
G03X181495Y205107I-1121J-664D01*
G03X181105Y205047I1J-1302D01*
G01X180989Y205011D01*
X179552Y206448D01*
X179588Y206564D01*
G03X179648Y206955I-1242J391D01*
G03X178346Y208257I-1302J0D01*
G03X177955Y208197I0J-1302D01*
G01X177839Y208161D01*
X176402Y209598D01*
X176438Y209714D01*
G03X176498Y210104I-1242J391D01*
G03X176417Y210557I-1302J1D01*
G01X176404Y210591D01*
Y212767D01*
X176417Y212801D01*
G03X176498Y213254I-1221J452D01*
G03X176417Y213707I-1302J1D01*
G01X176404Y213741D01*
Y215461D01*
X177057Y216113D01*
G03X177412Y216970I-857J857D01*
G01Y219900D01*
G03X177057Y220757I-1212J0D01*
G01X176812Y221002D01*
Y224583D01*
G02X177478Y224881I400J0D01*
G03X178346Y224550I867J971D01*
G03Y227154I0J1302D01*
G03X177317Y226650I0J-1302D01*
G02X176654Y226698I-315J246D01*
G03X176404Y227006I-1053J-599D01*
G01Y228515D01*
X176417Y228549D01*
G03X176498Y229002I-1221J452D01*
G03X176417Y229455I-1302J1D01*
G01X176404Y229489D01*
Y238982D01*
G03Y241018I-1103J1018D01*
G01Y245947D01*
X175116Y247235D01*
G02X175189Y247858I283J283D01*
G03X175902Y249136I-789J1278D01*
G03X175417Y250242I-1502J1D01*
G02Y250830I270J294D01*
G03X175902Y251936I-1017J1105D01*
G03X174400Y253438I-1502J0D01*
G03X172926Y252223I0J-1502D01*
G01X172914Y252163D01*
X172439Y251688D01*
G02X171845Y251719I-283J283D01*
G03X171766Y251807I-865J-697D01*
G01X170914Y252659D01*
Y254765D01*
X171969Y255821D01*
X171986Y255838D01*
G03X172021Y255874I-779J793D01*
G01X172024Y255878D01*
X173135Y256988D01*
G37*
G36*
G01X190229Y213936D02*
X194644D01*
X195900Y212680D01*
Y204912D01*
X194318Y203330D01*
Y197492D01*
X193982Y197156D01*
X192645D01*
G02X192245Y197545I0J400D01*
G03X190944Y198808I-1301J-39D01*
G03X189642Y197506I0J-1302D01*
G03X189648Y197376I1302J-5D01*
G01X189649Y197366D01*
Y197156D01*
X189089D01*
Y197366D01*
X189090Y197376D01*
G03X189096Y197506I-1296J125D01*
G03X186492I-1302J0D01*
G03X186498Y197376I1302J-5D01*
G01X186499Y197366D01*
Y197156D01*
X185940D01*
Y197366D01*
X185941Y197376D01*
G03X185947Y197506I-1296J125D01*
G03X183343I-1302J0D01*
G03X183349Y197376I1302J-5D01*
G01X183350Y197366D01*
Y197156D01*
X182790D01*
Y197366D01*
X182791Y197376D01*
G03X182797Y197506I-1296J125D01*
G03X181495Y198808I-1302J0D01*
G03X180325Y198076I0J-1301D01*
G02X179682Y197969I-360J176D01*
G01X179442Y198209D01*
G03X179049Y198602I-1096J-703D01*
G01X178809Y198842D01*
G02X178916Y199485I283J283D01*
G03X179648Y200655I-569J1170D01*
G03X178346Y201957I-1302J0D01*
G03X177050Y200781I0J-1302D01*
G01X177033Y200600D01*
X176509D01*
X176492Y200781D01*
G03X175196Y201957I-1296J-126D01*
G03X174051Y201275I0J-1302D01*
G02X173417Y201183I-351J191D01*
G01X171390Y203210D01*
Y209090D01*
X172200Y209900D01*
X173901D01*
X173942Y209754D01*
G03X175196Y208802I1254J350D01*
G03X175575Y208858I1J1302D01*
G01X175690Y208893D01*
X177135Y207448D01*
X177100Y207334D01*
G03X177044Y206955I1246J-378D01*
G03X178346Y205653I1302J0D01*
G03X178725Y205709I1J1302D01*
G01X178839Y205744D01*
X180284Y204299D01*
X180249Y204184D01*
G03X180193Y203805I1246J-378D01*
G03X181495Y202503I1302J0D01*
G03X182623Y203154I0J1303D01*
G01X183517D01*
G03X185773I1128J652D01*
G01X186872D01*
X186881Y203163D01*
X187622D01*
X189206Y204746D01*
X189330D01*
G02X189710Y204219I1J-400D01*
G03X189642Y203805I1234J-415D01*
G03X192246I1302J0D01*
G03X191936Y204649I-1302J1D01*
G02X191957Y205191I304J260D01*
G01X192772Y206005D01*
Y211105D01*
X191705Y212172D01*
X190528D01*
X190000Y212700D01*
Y213707D01*
X190229Y213936D01*
G37*
G36*
G01X191593Y234968D02*
G03X191646Y234969I0J1402D01*
G03X191693Y234968I53J1401D01*
G03X191737Y234969I-10J1402D01*
G02X191980Y234288I-40J-398D01*
G01X191189Y233497D01*
Y224397D01*
G02X190825Y223999I-400J0D01*
G03X189642Y222702I119J-1297D01*
G03X190944Y221400I1302J0D01*
G03X191230Y221432I-1J1302D01*
G01X191337Y221456D01*
X191731Y221061D01*
G02X191589Y220720I-142J-141D01*
G01X191523D01*
X191483Y220738D01*
G03X190944Y220855I-539J-1185D01*
G01X190923D01*
G03X189642Y219553I21J-1302D01*
G03X190944Y218251I1302J0D01*
G03X191144Y218266I3J1302D01*
G03X192246Y219532I-200J1287D01*
G01Y219543D01*
Y219553D01*
G03X192123Y220105I-1302J0D01*
G01X192104Y220146D01*
Y220390D01*
X192450D01*
G02X192837Y219891I0J-400D01*
G03X192792Y219559I1257J-339D01*
G01Y219541D01*
G03X195396I1302J12D01*
G01Y219554D01*
G03X195352Y219890I-1302J0D01*
G01X195351Y219893D01*
X195350Y219897D01*
G02X195738Y220390I389J93D01*
G01X196083D01*
Y220146D01*
X196064Y220105D01*
G03X195941Y219553I1179J-552D01*
G01Y219533D01*
G03X197243Y218251I1302J20D01*
G03X198545Y219553I0J1302D01*
G03X198530Y219750I-1301J0D01*
G01X198515Y219850D01*
X198728Y220063D01*
X199096Y219695D01*
X199092Y219607D01*
G03X199091Y219553I1301J-51D01*
G03X200393Y218251I1302J0D01*
G03X200447Y218252I3J1302D01*
G01X200535Y218256D01*
X202130Y216660D01*
X205630D01*
X207266Y215023D01*
Y211462D01*
X207519Y211210D01*
Y211209D01*
X207788Y210940D01*
X208255Y210474D01*
X208317D01*
X208545Y210246D01*
X208541Y210158D01*
G03X208540Y210104I1301J-51D01*
G03X209842Y208802I1302J0D01*
G03X210874Y209310I0J1302D01*
G01X211959D01*
G03X214023I1032J794D01*
G01X217100D01*
X218429Y207981D01*
X218298Y207840D01*
G03X217951Y206955I955J-885D01*
G03X219253Y205653I1302J0D01*
G03X219460Y205669I3J1302D01*
G01X219487Y205674D01*
G03X220138Y206000I-234J1281D01*
G01X220279Y206131D01*
X224763Y201647D01*
X233405D01*
G02X233780Y201108I0J-400D01*
G01X233774Y201092D01*
G03X233699Y200660I1227J-436D01*
G01Y200639D01*
G03X235001Y199353I1302J16D01*
G03X236303Y200655I0J1302D01*
G03X236302Y200709I-1302J3D01*
G02X236984Y201009I400J17D01*
G01X240063Y197930D01*
X240036Y197820D01*
G03X240000Y197582I1264J-313D01*
G03X239998Y197506I1300J-72D01*
G03X241284Y196204I1302J0D01*
G01X241301D01*
G03X241741Y196281I-1J1302D01*
G01X241774Y196293D01*
X243940D01*
X244008Y196281D01*
G03X244649Y196219I442J1225D01*
G03X244864Y196272I-203J1286D01*
G03X244892Y196281I-384J1244D01*
G01X244924Y196293D01*
X247089D01*
X247157Y196281D01*
G03X247798Y196219I442J1225D01*
G03X248013Y196272I-203J1286D01*
G03X248041Y196281I-384J1244D01*
G01X248073Y196293D01*
X250239D01*
X250307Y196281D01*
G03X250948Y196219I442J1225D01*
G03X251163Y196272I-203J1286D01*
G03X251191Y196281I-384J1244D01*
G01X251223Y196293D01*
X253388D01*
X253456Y196281D01*
G03X254097Y196219I442J1225D01*
G03X254312Y196272I-203J1286D01*
G03X254340Y196281I-384J1244D01*
G01X254372Y196293D01*
X256538D01*
X256606Y196281D01*
G03X257247Y196219I442J1225D01*
G03X257462Y196272I-203J1286D01*
G03X257490Y196281I-384J1244D01*
G01X257522Y196293D01*
X276439D01*
X276486Y196340D01*
X276555D01*
X284218Y204003D01*
G02X284878Y203853I283J-283D01*
G03X286105Y202986I1227J435D01*
G03X287256Y203680I0J1301D01*
G02X287958Y203690I354J-187D01*
G03X289091Y203029I1133J641D01*
G03Y205633I0J1302D01*
G03X287940Y204939I0J-1301D01*
G02X287238Y204929I-354J187D01*
G03X286540Y205515I-1133J-641D01*
G02X286390Y206175I133J377D01*
G01X289528Y209313D01*
X289581Y209327D01*
G03X290514Y210260I-327J1260D01*
G01X290528Y210313D01*
X290912Y210697D01*
X291103Y210506D01*
X291111Y210437D01*
G03X292404Y209285I1293J150D01*
G03X293706Y210587I0J1302D01*
G03X292554Y211880I-1302J0D01*
G01X292485Y211888D01*
X292294Y212079D01*
X292678Y212463D01*
X292731Y212477D01*
G03X293664Y213410I-327J1260D01*
G01X293678Y213463D01*
X301289Y221074D01*
X313650D01*
G03X314373Y220874I724J1211D01*
G01X314380D01*
X315754D01*
G02X316039Y220193I0J-400D01*
G03X315608Y219140I1071J-1053D01*
G03X318612I1502J0D01*
G03X318181Y220193I-1502J0D01*
G02X318466Y220874I285J281D01*
G01X339663D01*
X342921Y217616D01*
Y147385D01*
X339969Y144433D01*
X319345D01*
X319290Y144547D01*
G03X316582I-1354J-650D01*
G01X316527Y144433D01*
X315345D01*
X315290Y144547D01*
G03X312582I-1354J-650D01*
G01X312527Y144433D01*
X311345D01*
X311290Y144547D01*
G03X308582I-1354J-650D01*
G01X308527Y144433D01*
X307345D01*
X307290Y144547D01*
G03X304582I-1354J-650D01*
G01X304527Y144433D01*
X303345D01*
X303290Y144547D01*
G03X300582I-1354J-650D01*
G01X300527Y144433D01*
X298966D01*
X297354Y146046D01*
Y155240D01*
G03X297065Y156123I-1501J-3D01*
G01Y156124D01*
X297027Y156177D01*
Y156638D01*
X293975Y159690D01*
X283708D01*
X276278Y167121D01*
Y167153D01*
X270993Y172437D01*
X268332Y175099D01*
G02X268317Y175411I360J174D01*
G03X269224Y176791I-596J1380D01*
G03X268987Y177602I-1502J1D01*
G02X269183Y177858I389J-95D01*
G03X269187Y177860I-625J1255D01*
G03X269213Y177875I-688J1222D01*
G01X269364Y177963D01*
X269394Y177925D01*
G02X269807Y177525I13J-400D01*
G01Y177524D01*
G03X271209Y178926I1402J0D01*
G03X270511Y178740I0J-1403D01*
G02X269912Y179087I-199J347D01*
G01Y179088D01*
G03X267108I-1402J0D01*
G03X267142Y178781I1403J0D01*
G02X266752Y178294I-390J-87D01*
G01X265137D01*
X264272Y179159D01*
X264261Y179221D01*
G03X263124Y180358I-1381J-244D01*
G01X263062Y180369D01*
X257034Y186396D01*
X253999Y189432D01*
G02X254230Y189985I360J174D01*
G03X255200Y191244I-332J1259D01*
G03X253898Y192546I-1302J0D01*
G03X253698Y192531I-3J-1302D01*
G03X252597Y191306I200J-1287D01*
G01X252593Y191229D01*
X252397Y191033D01*
X252045Y191385D01*
X252035Y191449D01*
G03X250749Y192546I-1286J-205D01*
G03X250602Y192538I-3J-1302D01*
G01X250576Y192534D01*
G03X250512Y192524I169J-1291D01*
G01X250494Y192521D01*
X247854D01*
X247836Y192524D01*
G03X247599Y192546I-238J-1280D01*
G03X247362Y192524I1J-1302D01*
G01X247344Y192521D01*
X244705D01*
X244687Y192524D01*
G03X244450Y192546I-238J-1280D01*
G03X244213Y192524I1J-1302D01*
G01X244195Y192521D01*
X241555D01*
X241537Y192524D01*
G03X241300Y192546I-238J-1280D01*
G03X240009Y191410I0J-1302D01*
G01X240000Y191342D01*
X239465Y190807D01*
X238402Y189745D01*
Y189723D01*
X235780Y187100D01*
X220847D01*
G02X220473Y187640I1J400D01*
G03X220555Y188095I-1221J455D01*
G03X217951I-1302J0D01*
G03X218033Y187640I1303J0D01*
G02X217659Y187100I-375J-140D01*
G01X216392D01*
X209476Y194016D01*
X207434D01*
X205440Y196010D01*
X204844D01*
G02X204538Y196668I0J400D01*
G03X204844Y197506I-996J838D01*
G03X202240I-1302J0D01*
G03X202693Y196519I1302J0D01*
G02X202511Y196174I-130J-152D01*
G03X202201Y196214I-309J-1171D01*
G01X199242D01*
X198735Y196721D01*
X198426D01*
Y196962D01*
X198442Y196999D01*
G03X198545Y197506I-1199J508D01*
G03X197243Y198808I-1302J0D01*
G03X196429Y198522I0J-1301D01*
G02X195801Y198851I-228J329D01*
G01Y199310D01*
G02X196429Y199639I400J0D01*
G03X197243Y199353I814J1015D01*
G03Y201957I0J1302D01*
G03X196429Y201671I0J-1301D01*
G02X195801Y202000I-228J329D01*
G01Y202460D01*
G02X196429Y202789I400J0D01*
G03X197243Y202503I814J1015D01*
G03X198545Y203805I0J1302D01*
G03X197249Y205107I-1302J0D01*
G02X197050Y205307I1J200D01*
G01Y213640D01*
X195740Y214950D01*
X187650D01*
X185206Y217394D01*
Y218378D01*
G03Y220728I-561J1175D01*
G01Y221528D01*
G03Y223878I-561J1175D01*
G01Y224677D01*
G03Y227027I-561J1175D01*
G01Y227827D01*
G03Y230177I-561J1175D01*
G01Y230976D01*
G03Y233326I-561J1175D01*
G01Y246443D01*
X185213Y246450D01*
Y248056D01*
G02X185652Y248454I400J0D01*
G03X185897Y248434I244J1482D01*
G03X187398Y249870I0J1502D01*
G01X187400Y249916D01*
Y249936D01*
G03X186985Y250973I-1503J0D01*
G01X192199Y256187D01*
G03X192766Y255932I886J1213D01*
G02X193078Y255488I-84J-391D01*
G03X193065Y255288I1489J-197D01*
G03X196069I1502J0D01*
G03X194714Y256783I-1502J0D01*
G02X194540Y257031I20J199D01*
G03X194572Y257193I-1455J372D01*
G01X194596Y257365D01*
X199180D01*
X199215Y257209D01*
G03X200680Y256038I1465J331D01*
G03X200727Y256039I-8J1502D01*
G02X201140Y255639I13J-400D01*
G01Y253099D01*
X192641Y244600D01*
Y238051D01*
G02X192260Y237652I-400J0D01*
G03X191693Y237772I-567J-1282D01*
G03X191644Y237771I4J-1402D01*
G03X191595Y237772I-53J-1401D01*
G01X191593D01*
G03Y234968I0J-1402D01*
G37*
G36*
G01X233326Y268135D02*
X236575D01*
X239884Y264826D01*
Y264727D01*
G02X239284Y264381I-400J0D01*
G03X238531Y264583I-752J-1300D01*
G03Y261579I0J-1502D01*
G03X239284Y261781I1J1502D01*
G02X239884Y261435I200J-346D01*
G01Y255334D01*
X230616Y246066D01*
X230533D01*
G03X229033Y244566I2J-1502D01*
G01Y244483D01*
X222078Y237528D01*
G02X221419Y237675I-283J283D01*
G03X220100Y238602I-1319J-475D01*
G03X218698Y237200I0J-1402D01*
G03X219625Y235881I1402J0D01*
G02X219772Y235222I-136J-376D01*
G01X214475Y229925D01*
G02X213910Y229924I-283J283D01*
G03X212991Y230304I-919J-921D01*
G03X211689Y229002I0J-1302D01*
G03X212199Y227969I1301J0D01*
G01X212209Y227961D01*
X212360Y227810D01*
X212027Y227477D01*
X211119D01*
G02X210819Y228141I0J400D01*
G03X211144Y229002I-978J861D01*
G03X208540I-1302J0D01*
G03X208865Y228141I1303J0D01*
G02X208565Y227477I-300J-264D01*
G01X207969D01*
G02X207669Y228141I0J400D01*
G03X207994Y229002I-978J861D01*
G03X205390I-1302J0D01*
G03X205715Y228141I1303J0D01*
G02X205415Y227477I-300J-264D01*
G01X204819D01*
G02X204519Y228141I0J400D01*
G03X204844Y229002I-978J861D01*
G03X202240I-1302J0D01*
G03X202565Y228141I1303J0D01*
G02X202265Y227477I-300J-264D01*
G01X201900D01*
X201691Y227686D01*
X201398D01*
X201264Y228035D01*
G03X201695Y229002I-871J968D01*
G03X199091I-1302J0D01*
G03X199522Y228035I1302J1D01*
G01X199588Y227975D01*
Y227686D01*
X199335D01*
X198294Y226645D01*
X198153Y226783D01*
G03X197243Y227154I-910J-931D01*
G03Y224550I0J-1302D01*
G03X197715Y224639I-1J1302D01*
G02X198260Y224266I145J-373D01*
G01Y222033D01*
X197619Y221392D01*
X195532D01*
G02X195194Y222006I0J400D01*
G03X195396Y222703I-1100J697D01*
G03X192792I-1302J0D01*
G03X193218Y221740I1301J0D01*
G01X193283Y221680D01*
Y221392D01*
X192817D01*
X192244Y221965D01*
Y222635D01*
G03X192246Y222702I-1300J72D01*
G03X192244Y222769I-1302J-5D01*
G01Y233032D01*
X193004Y233792D01*
X193251D01*
X193462Y233580D01*
G02X193424Y233267I-141J-142D01*
G03X192792Y232151I669J-1116D01*
G03X195396I1302J0D01*
G03X195249Y232751I-1302J-1D01*
G02X195604Y233336I355J185D01*
G01X195733D01*
G02X196088Y232751I0J-400D01*
G03X195941Y232151I1155J-601D01*
G03X198545I1302J0D01*
G03X198398Y232751I-1302J-1D01*
G02X198753Y233336I355J185D01*
G01X198883D01*
G02X199238Y232751I0J-400D01*
G03X199091Y232151I1155J-601D01*
G03X201695I1302J0D01*
G03X200979Y233314I-1303J0D01*
G01X200951Y233328D01*
X200786Y233492D01*
X201086Y233792D01*
X202333D01*
X202556Y233569D01*
G02X202572Y233019I-282J-283D01*
G03X202240Y232151I969J-868D01*
G03X204844I1302J0D01*
G03X204778Y232559I-1302J-1D01*
G02X205158Y233084I380J125D01*
G01X205581D01*
Y232832D01*
X205556Y232786D01*
G03X205390Y232151I1136J-636D01*
G03X207994I1302J0D01*
G03X207928Y232559I-1302J-1D01*
G02X208308Y233084I380J125D01*
G01X208731D01*
Y232832D01*
X208706Y232786D01*
G03X208540Y232151I1136J-636D01*
G03X211144I1302J0D01*
G03X210830Y232999I-1302J0D01*
G02X210840Y233271I151J131D01*
G01X219441Y241872D01*
G02X219992Y241886I283J-283D01*
G03X221000Y241498I1008J1115D01*
G03X222502Y243000I0J1502D01*
G03X222114Y244008I-1503J0D01*
G02X222128Y244559I297J268D01*
G01X223204Y245635D01*
G02X223863Y245488I283J-283D01*
G03X225275Y244498I1412J512D01*
G03X226777Y246000I0J1502D01*
G03X225787Y247412I-1502J0D01*
G02X225640Y248071I136J376D01*
G01X232773Y255204D01*
Y259768D01*
X232894Y259820D01*
G03X233802Y261200I-595J1380D01*
G03X232798Y262617I-1502J0D01*
G01X232755Y262632D01*
X231160Y264227D01*
Y266325D01*
G03X231697Y267410I-964J1152D01*
G01X231700Y267488D01*
X232311Y268099D01*
X232420Y268072D01*
G03X232773Y268030I353J1460D01*
G03X233292Y268123I-1J1502D01*
G01X233326Y268135D01*
G37*
G36*
G01X214601Y274920D02*
X222322D01*
X222738Y274504D01*
Y272784D01*
X220699Y268387D01*
X220519Y268469D01*
G03X219900Y268602I-618J-1369D01*
G03X218398Y267100I0J-1502D01*
G03X219032Y265874I1502J0D01*
G02X219139Y265333I-231J-327D01*
G01X219074Y265231D01*
G02X218477Y265141I-338J214D01*
G03X217500Y265502I-977J-1142D01*
G03X215998Y264000I0J-1502D01*
G03X216885Y262629I1503J0D01*
G02X217060Y262050I-163J-365D01*
G01X208241Y248130D01*
G02X207514Y248253I-338J214D01*
G03X206051Y249413I-1463J-343D01*
G03Y246409I0J-1502D01*
G03X206367Y246443I-2J1502D01*
G02X206789Y245838I84J-391D01*
G01X205523Y243839D01*
X201214Y237290D01*
Y235336D01*
X200215Y234337D01*
X194122D01*
X193675Y234784D01*
Y244106D01*
X196946Y247377D01*
G02X197599Y247245I283J-283D01*
G03X198990Y246309I1391J566D01*
G03X200492Y247811I0J1502D01*
G03X199556Y249202I-1502J0D01*
G02X199424Y249855I151J370D01*
G01X203055Y253486D01*
Y263374D01*
X204786Y265105D01*
X204927Y264986D01*
G03X205900Y264628I973J1143D01*
G03X207402Y266130I0J1502D01*
G03X207044Y267103I-1501J0D01*
G01X206925Y267244D01*
X212040Y272359D01*
X212182Y272217D01*
X212183Y272216D01*
G03X213258Y271763I1075J1049D01*
G03X214760Y273265I0J1502D01*
G03X214307Y274340I-1502J0D01*
G01X214306Y274341D01*
X214164Y274483D01*
X214601Y274920D01*
G37*
G36*
G01X254860Y275259D02*
X255812D01*
X256618Y274454D01*
Y271060D01*
X254350Y268792D01*
Y262370D01*
X254884Y261836D01*
G02X254833Y261226I-282J-284D01*
G03X254198Y260000I866J-1226D01*
G03X255700Y258498I1502J0D01*
G03X256109Y258555I-1J1502D01*
G02X256618Y258170I109J-385D01*
G01Y237671D01*
X255272Y236325D01*
G02X254733Y236301I-283J283D01*
G03X253898Y236604I-835J-999D01*
G01X250749D01*
G03X250697Y236602I24J-1302D01*
G02X250516Y236902I-8J200D01*
G03X250702Y237600I-1217J698D01*
G03X247898I-1402J0D01*
G03X249163Y236205I1402J0D01*
G02X249505Y235688I-40J-398D01*
G03X249446Y235301I1244J-388D01*
G03X250749Y233998I1303J0D01*
G01X251980D01*
G02X252263Y233316I0J-400D01*
G01X252122Y233175D01*
G02X251583Y233151I-283J283D01*
G03X250749Y233453I-834J-1001D01*
G03X249447Y232151I0J-1302D01*
G03X249523Y231714I1302J1D01*
G03X249143Y231457I477J-1114D01*
G01X248992Y231305D01*
X248757Y231540D01*
X248807Y231663D01*
G03X248902Y232151I-1208J488D01*
G03X247599Y233454I-1303J0D01*
G01X244450D01*
G03Y230848I0J-1303D01*
G01X247599D01*
G03X248087Y230943I0J1303D01*
G01X248210Y230993D01*
X248445Y230758D01*
X246780Y229094D01*
G03X246458Y228516I857J-856D01*
G01X246422Y228362D01*
X246172D01*
G02X245776Y228818I0J400D01*
G03X245789Y229002I-1289J184D01*
G03X243185I-1302J0D01*
G03X243242Y228621I1302J0D01*
G01X243251Y228592D01*
Y228362D01*
X242602D01*
Y229002D01*
G03X239998I-1302J0D01*
G01Y228362D01*
X236717D01*
G02X236323Y228827I1J400D01*
G03X236340Y229039I-1285J210D01*
G03X233736I-1302J0D01*
G03X233811Y228604I1302J1D01*
G01X233853Y228485D01*
X233550Y228182D01*
X233019D01*
Y228426D01*
X233037Y228465D01*
G03X233153Y229002I-1185J537D01*
G03X231851Y227700I-1302J0D01*
G03X231955Y227704I2J1302D01*
G01X232047Y227711D01*
X232253Y227505D01*
X231942Y227193D01*
X231862Y227192D01*
G03X230587Y225917I27J-1302D01*
G01X230586Y225837D01*
X230239Y225490D01*
X230035Y225695D01*
X230039Y225784D01*
G03X230041Y225852I-1300J72D01*
G03X228739Y224550I-1302J0D01*
G03X228807Y224552I-4J1302D01*
G01X228896Y224556D01*
X229101Y224352D01*
X228756Y224007D01*
X228678Y224004D01*
G03X227438Y222764I61J-1301D01*
G01X227435Y222686D01*
X227089Y222340D01*
X226883Y222546D01*
X226889Y222636D01*
G03X226892Y222720I-1299J88D01*
G03X225590Y221418I-1302J0D01*
G03X225674Y221421I-4J1302D01*
G01X225764Y221427D01*
X225970Y221221D01*
X225605Y220856D01*
X225525Y220855D01*
G03X224250Y219580I27J-1302D01*
G01X224249Y219500D01*
X223899Y219151D01*
X223693Y219357D01*
X223700Y219449D01*
G03X223704Y219553I-1298J102D01*
G03X222402Y218251I-1302J0D01*
G03X223139Y218480I0J1302D01*
G02X223452Y218315I113J-165D01*
G01Y218085D01*
X219807Y214439D01*
X219688Y214481D01*
G03X219253Y214556I-436J-1227D01*
G03X217951Y213254I0J-1302D01*
G03X218026Y212819I1302J1D01*
G01X218068Y212700D01*
X216843Y211475D01*
X208670D01*
X208268Y211877D01*
Y215889D01*
X208999Y216620D01*
X212795D01*
X212838Y216662D01*
X212888D01*
X214898Y218672D01*
G02X215181I142J-141D01*
G03X216103Y218289I922J918D01*
G03X217405Y219591I0J1302D01*
G03X217022Y220513I-1301J0D01*
G01X216880Y220655D01*
X217910Y221685D01*
G02X218451Y221708I283J-283D01*
G03X219290Y221401I840J995D01*
G03X220592Y222703I0J1302D01*
G03X220285Y223542I-1302J-1D01*
G02X220308Y224083I306J258D01*
G01X221059Y224834D01*
G02X221600Y224857I283J-283D01*
G03X222440Y224550I840J996D01*
G03X223742Y225852I0J1302D01*
G03X223435Y226692I-1303J0D01*
G02X223458Y227233I306J258D01*
G01X224192Y227967D01*
G02X224728Y227994I283J-283D01*
G03X225552Y227700I824J1008D01*
G03X226854Y229002I0J1302D01*
G03X226543Y229847I-1302J0D01*
G02X226564Y230389I304J260D01*
G01X249161Y252986D01*
Y274394D01*
X250026Y275259D01*
X251916D01*
G02X252225Y274606I-1J-400D01*
G03X251886Y273655I1163J-951D01*
G03X254890I1502J0D01*
G03X254551Y274606I-1502J0D01*
G02X254860Y275259I310J253D01*
G37*
G36*
G01X248245Y287789D02*
X253781D01*
X254380Y287190D01*
Y277376D01*
X253456Y276452D01*
X248714D01*
X247580Y275318D01*
Y271690D01*
G02X247391Y271490I-200J0D01*
G03Y268490I79J-1500D01*
G02X247580Y268290I-11J-200D01*
G01Y253306D01*
X224672Y230399D01*
Y229962D01*
G03X224395Y229600I880J-960D01*
G01X224381Y229572D01*
X224234Y229425D01*
G02X223587Y229542I-283J283D01*
G03X222402Y230304I-1185J-540D01*
G03X221100Y229002I0J-1302D01*
G03X221862Y227817I1302J0D01*
G02X221979Y227170I-166J-364D01*
G01X221788Y226979D01*
G03X221313Y226504I652J-1127D01*
G01X221110Y226301D01*
G02X220466Y226412I-283J283D01*
G03X219290Y227154I-1176J-561D01*
G03X217988Y225852I0J-1302D01*
G03X218730Y224676I1303J0D01*
G02X218841Y224032I-172J-361D01*
G01X218640Y223831D01*
G03X218162Y223353I650J-1128D01*
G01X217961Y223152D01*
G02X217317Y223263I-283J283D01*
G03X216141Y224005I-1176J-561D01*
G03X214839Y222703I0J-1302D01*
G03X215581Y221527I1303J0D01*
G02X215692Y220883I-172J-361D01*
G01X215603Y220794D01*
X215569Y220778D01*
G03X214916Y220125I534J-1187D01*
G01X214900Y220091D01*
X214811Y220002D01*
G02X214167Y220113I-283J283D01*
G03X212991Y220855I-1176J-561D01*
G03X211689Y219553I0J-1302D01*
G03X212431Y218377I1303J0D01*
G02X212542Y217733I-172J-361D01*
G01X212473Y217664D01*
X202830D01*
X201551Y218943D01*
X201600Y219066D01*
G03X201695Y219553I-1207J488D01*
G03X200393Y220855I-1302J0D01*
G03X199906Y220760I1J-1302D01*
G01X199783Y220711D01*
X199284Y221210D01*
Y221507D01*
G02X199605Y221667I200J1D01*
G03X200393Y221401I789J1036D01*
G03Y224005I0J1302D01*
G03X199851Y223887I0J-1302D01*
G02X199284Y224250I-167J363D01*
G01Y225889D01*
X200080Y226684D01*
X201276D01*
X201485Y226476D01*
X201855D01*
G02X202251Y226023I-1J-400D01*
G03X202240Y225852I1291J-169D01*
G03X204844I1302J0D01*
G03X204833Y226023I-1302J2D01*
G02X205229Y226476I397J53D01*
G01X205451D01*
Y226247D01*
X205443Y226219D01*
G03X205390Y225852I1249J-368D01*
G03X207994I1302J0D01*
G03X207983Y226023I-1302J2D01*
G02X208379Y226476I397J53D01*
G01X208601D01*
Y226247D01*
X208593Y226219D01*
G03X208540Y225852I1249J-368D01*
G03X211144I1302J0D01*
G03X211133Y226023I-1302J2D01*
G02X211529Y226476I397J53D01*
G01X211739D01*
Y226249D01*
X211733Y226224D01*
G03X211689Y225890I1258J-336D01*
G03X214293I1302J0D01*
G03X213730Y226962I-1302J0D01*
G02X213674Y227574I227J329D01*
G01X217569Y231468D01*
G02X218181Y231412I283J-283D01*
G03X219253Y230849I1072J739D01*
G03X220555Y232151I0J1302D01*
G03X219992Y233223I-1302J0D01*
G02X219936Y233835I227J329D01*
G01X229533Y243432D01*
X229671Y243336D01*
G03X230535Y243062I865J1228D01*
G03X232037Y244564I0J1502D01*
G03X231763Y245428I-1502J-1D01*
G01X231667Y245566D01*
X240750Y254649D01*
G02X241381Y254563I283J-283D01*
G03X242690Y253798I1309J737D01*
G03Y256802I0J1502D01*
G03X241685Y256417I-1J-1502D01*
G02X241018Y256714I-267J297D01*
G01Y265107D01*
X240886Y265240D01*
Y265241D01*
X239459Y266668D01*
G02X239648Y267339I283J282D01*
G03X240800Y268800I-350J1461D01*
G03X239298Y270302I-1502J0D01*
G03X238287Y269911I0J-1503D01*
G02X237618Y270207I-269J296D01*
G01Y273433D01*
X247396Y283211D01*
Y285766D01*
X247410Y285780D01*
Y286954D01*
X248245Y287789D01*
G37*
G36*
G01X247440Y298853D02*
X248325D01*
X249608Y297570D01*
Y293572D01*
X246176Y290140D01*
Y284362D01*
X242236Y280422D01*
G03X241188Y280849I-1049J-1075D01*
G03X239686Y279347I0J-1502D01*
G03X239998Y278430I1502J0D01*
G01X240105Y278291D01*
X234079Y272265D01*
G02X233397Y272580I-283J282D01*
G03X233402Y272700I-1497J122D01*
G03X230398I-1502J0D01*
G03X231515Y271248I1502J0D01*
G02X231699Y270582I-102J-387D01*
G03X231271Y269539I1074J-1050D01*
G01Y269457D01*
X230708Y268894D01*
X230596Y268925D01*
G03X230196Y268979I-399J-1448D01*
G03X228694Y267477I0J-1502D01*
G03X229130Y266419I1502J0D01*
G02X229011Y265773I-284J-282D01*
G03X228128Y264404I620J-1369D01*
G03X229604Y262902I1502J0D01*
G02X229800Y262702I-4J-200D01*
G01Y257197D01*
X229647Y257160D01*
G03X229285Y257021I353J-1460D01*
G02X228721Y257231I-190J352D01*
G03X227316Y258202I-1405J-531D01*
G03Y255198I0J-1502D01*
G03X228031Y255379I0J1503D01*
G02X228595Y255169I190J-352D01*
G03X228922Y254654I1405J531D01*
G02X228918Y254092I-287J-279D01*
G01X211187Y236361D01*
G02X210632Y236351I-283J283D01*
G03X209746Y236699I-886J-954D01*
G03X208444Y235397I0J-1302D01*
G03X208627Y234732I1302J1D01*
G02X208283Y234128I-344J-204D01*
G01X203436D01*
X202515Y235049D01*
Y236373D01*
X214631Y256345D01*
X220556Y265698D01*
X220586Y265762D01*
X220641Y265794D01*
G03X221402Y267100I-740J1306D01*
G03X221390Y267292I-1502J2D01*
G01X221381Y267362D01*
X224063Y271734D01*
Y273895D01*
X225723Y275555D01*
G02X226392Y275378I283J-283D01*
G03X226518Y275062I1449J395D01*
G02X226236Y274479I-352J-189D01*
G03X224998Y273000I264J-1479D01*
G03X225727Y271712I1502J0D01*
G02X225881Y271195I-206J-343D01*
G03X225730Y270539I1351J-656D01*
G03X228734I1502J0D01*
G03X228005Y271827I-1502J0D01*
G02X227851Y272344I206J343D01*
G03X228002Y273000I-1351J656D01*
G03X227823Y273711I-1502J0D01*
G02X228105Y274294I352J189D01*
G03X229343Y275773I-264J1479D01*
G03X228236Y277222I-1502J0D01*
G02X228059Y277891I106J386D01*
G01X228505Y278337D01*
X230861D01*
X236335Y283811D01*
Y287755D01*
X238857Y290276D01*
G03X239212Y291133I-857J857D01*
G01Y293556D01*
X244508Y298853D01*
X244960D01*
G03X247440I1240J846D01*
G37*
G36*
G01X217952Y115769D02*
X231272D01*
Y111975D01*
X231133Y111930D01*
G03Y109070I459J-1430D01*
G01X231272Y109025D01*
Y105350D01*
X217952D01*
Y115769D01*
G37*
G36*
G01X255053Y228400D02*
X267400D01*
X269582Y226218D01*
Y225182D01*
X269670Y225094D01*
Y220732D01*
X268721Y219783D01*
X258338D01*
X258296Y219926D01*
G03X255800I-1248J-374D01*
G01X255758Y219783D01*
X255188D01*
X255146Y219926D01*
G03X252650I-1248J-374D01*
G01X252608Y219783D01*
X252039D01*
X251997Y219926D01*
G03X249501I-1248J-374D01*
G01X249459Y219783D01*
X239440D01*
X239398Y219926D01*
G03X236902I-1248J-374D01*
G01X236860Y219783D01*
X236291D01*
X236249Y219926D01*
G03X235001Y220855I-1248J-374D01*
G03X233699Y219553I0J-1302D01*
G03X233871Y218906I1303J0D01*
G01X233947Y218773D01*
X229762Y214588D01*
Y214510D01*
G02X229452Y214343I-200J0D01*
G03X228739Y214556I-714J-1089D01*
G03Y211952I0J-1302D01*
G03X229216Y212042I1J1302D01*
G02X229762Y211670I146J-372D01*
G01Y211335D01*
G02X229448Y211171I-200J0D01*
G03X228702Y211406I-746J-1067D01*
G03Y208802I0J-1302D01*
G03X229207Y208904I0J1301D01*
G02X229762Y208535I155J-369D01*
G01Y203482D01*
X229194Y202914D01*
X225699D01*
X224454Y204159D01*
Y218289D01*
X224718Y218553D01*
G03X225552Y218251I834J1001D01*
G03X226854Y219553I0J1302D01*
G03X226646Y220258I-1302J-1D01*
G01X226559Y220394D01*
X227878Y221713D01*
X228014Y221621D01*
G03X228739Y221401I724J1082D01*
G03X230041Y222703I0J1302D01*
G03X229821Y223428I-1302J1D01*
G01X229729Y223564D01*
X231048Y224883D01*
X231184Y224796D01*
G03X231889Y224588I706J1094D01*
G03X233191Y225890I0J1302D01*
G03X232889Y226724I-1303J0D01*
G01X233346Y227181D01*
X233588D01*
G02X233929Y226572I0J-400D01*
G03X233736Y225890I1108J-682D01*
G03X236340I1302J0D01*
G03X236147Y226572I-1301J0D01*
G02X236488Y227181I341J209D01*
G01X236762D01*
G02X237097Y226563I0J-400D01*
G03X236886Y225852I1091J-711D01*
G03X239490I1302J0D01*
G03X239279Y226563I-1302J0D01*
G02X239614Y227181I335J218D01*
G01X239998D01*
Y225853D01*
G03X241300Y224550I1303J0D01*
G03X242236Y224947I0J1302D01*
G03X242640Y225890I-899J943D01*
G03X242607Y226179I-1302J-2D01*
G01X242602Y226201D01*
Y227181D01*
X246426D01*
Y226330D01*
X246413Y226297D01*
G03X246335Y225852I1224J-444D01*
G03X248939I1302J0D01*
G03X248861Y226297I-1302J1D01*
G01X248848Y226330D01*
Y227348D01*
X249563Y228063D01*
G02X249844Y228066I142J-141D01*
G03X250749Y227700I905J936D01*
G01X253898D01*
G03X255053Y228400I0J1303D01*
G37*
G36*
G01X248706Y190558D02*
X249642D01*
G03X250749Y189942I1107J687D01*
G03X251680Y190334I0J1302D01*
G01X261827Y180187D01*
G02X261835Y179912I-141J-142D01*
G03X261478Y178977I1046J-935D01*
G03X262487Y177631I1402J0D01*
G02X262763Y177151I-112J-384D01*
G03X262720Y176791I1459J-357D01*
G03X264222Y175288I1503J0D01*
G01X266725D01*
X275276Y166738D01*
Y164430D01*
X274654Y163808D01*
X274541Y163841D01*
G03X274128Y163898I-410J-1444D01*
G01X265362D01*
X264830Y164431D01*
G03X264298Y164774I-1061J-1062D01*
G01X264258Y164789D01*
X258073Y170974D01*
G02X258048Y171513I282J283D01*
G03X258350Y172347I-1001J834D01*
G03X257067Y173649I-1302J0D01*
G02X256674Y174049I7J400D01*
G01Y176068D01*
G03X256319Y176925I-1212J0D01*
G01X255381Y177863D01*
G03X255073Y178086I-856J-858D01*
G03X255200Y178646I-1175J561D01*
G03X252596I-1302J0D01*
G03X252606Y178485I1301J0D01*
G01X252608Y178473D01*
Y178260D01*
X252039D01*
Y178473D01*
X252041Y178485D01*
G03X252051Y178646I-1291J161D01*
G03X250749Y179948I-1302J0D01*
G03X250315Y179874I-1J-1302D01*
G03X250057Y180256I-1115J-475D01*
G02X250272Y180584I141J142D01*
G03X250749Y180493I478J1211D01*
G03X249447Y181795I0J1302D01*
G03X249538Y181318I1302J1D01*
G01X249586Y181196D01*
X249351Y180962D01*
X249172Y181142D01*
G03X248833Y181380I-855J-858D01*
G03X248901Y181795I-1234J415D01*
G03X247599Y183097I-1302J0D01*
G03X247063Y182981I1J-1302D01*
G03X246857Y183257I-1064J-579D01*
G01X245889Y184225D01*
G03X245640Y184416I-856J-858D01*
G03X245752Y184945I-1190J528D01*
G03X243148I-1302J0D01*
G03X243155Y184806I1302J-4D01*
G01X243157Y184796D01*
Y184585D01*
X242593D01*
Y184796D01*
X242595Y184806D01*
G03X242602Y184945I-1295J135D01*
G03X241300Y186247I-1302J0D01*
G03X240016Y185158I0J-1301D01*
G01X240005Y185095D01*
X239818Y184908D01*
X239395Y185331D01*
Y188123D01*
X239404Y188132D01*
Y189330D01*
X240388Y190314D01*
G03X241300Y189942I911J930D01*
G03X242407Y190558I0J1303D01*
G01X243343D01*
G03X245557I1107J687D01*
G01X246492D01*
G03X248706I1107J687D01*
G37*
G36*
G01X287400Y236442D02*
X290822D01*
X291600Y235664D01*
Y233700D01*
X291334Y233434D01*
Y224151D01*
X272779Y205596D01*
X269673D01*
G02X269389Y206277I0J400D01*
G03X269793Y207262I-999J985D01*
G03X268391Y208664I-1402J0D01*
G03X267443Y208295I0J-1402D01*
G02X267163Y208303I-136J147D01*
G03X266080Y208764I-1083J-1042D01*
G01X262580D01*
G03X261589Y208392I-1J-1502D01*
G02X261077Y208379I-264J300D01*
G03X260269Y208660I-808J-1021D01*
G03Y206056I0J-1302D01*
G03X260990Y206274I0J1301D01*
G02X261499Y206218I221J-333D01*
G03X261816Y205968I1081J1044D01*
G01X261714Y205596D01*
X258454D01*
G02X258124Y206221I0J400D01*
G03X258350Y206955I-1076J733D01*
G03X255746I-1302J0D01*
G03X255972Y206221I1302J-1D01*
G02X255642Y205596I-330J-225D01*
G01X255304D01*
G02X254974Y206221I0J400D01*
G03X255200Y206955I-1076J733D01*
G03X252596I-1302J0D01*
G03X252822Y206221I1302J-1D01*
G02X252492Y205596I-330J-225D01*
G01X252155D01*
G02X251825Y206221I0J400D01*
G03X252051Y206955I-1076J733D01*
G03X249447I-1302J0D01*
G03X249673Y206221I1302J-1D01*
G02X249343Y205596I-330J-225D01*
G01X249005D01*
G02X248675Y206221I0J400D01*
G03X248901Y206955I-1076J733D01*
G03X246297I-1302J0D01*
G03X246523Y206221I1302J-1D01*
G02X246193Y205596I-330J-225D01*
G01X242673D01*
X239759Y202682D01*
X234584D01*
X234056Y203210D01*
Y204135D01*
X239512Y209591D01*
G02X240149Y209496I283J-282D01*
G03X241300Y208802I1151J607D01*
G03X242602Y210104I0J1302D01*
G03X241684Y211348I-1302J0D01*
G01X241637Y211363D01*
X241460Y211539D01*
X241798Y211877D01*
X271620D01*
X271756Y212012D01*
X271803D01*
X286662Y226872D01*
Y233846D01*
X287102Y234285D01*
Y236143D01*
X287400Y236442D01*
G37*
G36*
G01X279461Y236361D02*
X285639D01*
X286100Y235900D01*
Y234700D01*
X285661Y234261D01*
Y227287D01*
X271388Y213014D01*
X270754D01*
G02X270451Y213676I-1J400D01*
G03X270793Y214593I-1060J918D01*
G03X269391Y215995I-1402J0D01*
G03X268443Y215626I0J-1402D01*
G02X268163Y215634I-136J147D01*
G03X267080Y216096I-1084J-1041D01*
G01X263580D01*
G03X262526Y215663I1J-1502D01*
G02X262246I-140J143D01*
G03X261269Y216059I-977J-1007D01*
G03X259867Y214657I0J-1402D01*
G03X260254Y213690I1402J0D01*
G02X259964Y213014I-290J-276D01*
G01X258742D01*
G02X258344Y213376I0J400D01*
G03X257048Y214556I-1296J-122D01*
G03X255746Y213254I0J-1302D01*
G01Y213219D01*
X255747Y213217D01*
Y213014D01*
X255199D01*
Y213217D01*
X255200Y213219D01*
Y213254D01*
G03X252596I-1302J0D01*
G01Y213219D01*
X252597Y213217D01*
Y213014D01*
X252050D01*
Y213217D01*
X252051Y213219D01*
Y213254D01*
G03X249447I-1302J0D01*
G01Y213219D01*
X249448Y213217D01*
Y213014D01*
X248900D01*
Y213217D01*
X248901Y213219D01*
Y213254D01*
G03X247599Y214556I-1302J0D01*
G03X246303Y213376I0J-1302D01*
G02X245905Y213014I-398J38D01*
G01X242994D01*
G02X242596Y213376I0J400D01*
G03X241300Y214556I-1296J-122D01*
G03X239998Y213254I0J-1302D01*
G03X240330Y212386I1301J0D01*
G02X240314Y211836I-298J-267D01*
G01X237592Y209114D01*
Y209088D01*
X236432Y207928D01*
G02X235880Y207916I-282J283D01*
G03X235001Y208257I-879J-962D01*
G03X233699Y206955I0J-1302D01*
G03X234040Y206076I1303J0D01*
G02X234028Y205524I-295J-270D01*
G01X232993Y204489D01*
Y203252D01*
X232507Y202766D01*
X231339D01*
X230988Y203118D01*
X230877Y203229D01*
Y208502D01*
G02X231412Y208878I400J0D01*
G03X231851Y208802I438J1226D01*
G03Y211406I0J1302D01*
G03X231412Y211330I-1J-1302D01*
G02X230877Y211706I-135J376D01*
G01Y213238D01*
X236421Y218782D01*
X237101D01*
G03X239199I1049J771D01*
G01X249700D01*
G03X251798I1049J771D01*
G01X252849D01*
G03X254947I1049J771D01*
G01X255999D01*
G03X258097I1049J771D01*
G01X269136D01*
X269142Y218788D01*
X269913D01*
X271561Y220436D01*
Y220456D01*
X278930Y227824D01*
Y235830D01*
X279461Y236361D01*
G37*
G36*
G01X300542Y255442D02*
X306434D01*
G03X307500Y254998I1066J1058D01*
G03X307692Y255010I2J1502D01*
G01X307790Y255023D01*
X308266Y254547D01*
Y242752D01*
G03X308679Y241754I1412J0D01*
G01X309541Y240892D01*
Y240254D01*
X309362Y240235D01*
G03Y237247I159J-1494D01*
G01X309541Y237228D01*
Y236865D01*
X309362Y236846D01*
G03Y233858I159J-1494D01*
G01X309541Y233839D01*
Y231299D01*
X309362Y231280D01*
G03X308019Y229786I159J-1494D01*
G03X308067Y229408I1502J-1D01*
G01X308096Y229297D01*
X296324Y217525D01*
X296277Y217510D01*
G03X295303Y216536I457J-1431D01*
G01X295288Y216489D01*
X293398Y214599D01*
X293257Y214721D01*
G03X292404Y215039I-853J-985D01*
G03X291102Y213737I0J-1302D01*
G03X291420Y212884I1303J0D01*
G02X291411Y212612I-151J-131D01*
G01X290379Y211580D01*
G02X290107Y211571I-141J142D01*
G03X289254Y211889I-853J-985D01*
G03X287952Y210587I0J-1302D01*
G03X288270Y209734I1303J0D01*
G01X288392Y209593D01*
X276140Y197341D01*
X258354D01*
X258350Y197536D01*
G03X255746I-1302J-30D01*
G01X255742Y197341D01*
X255204D01*
X255200Y197536D01*
G03X252596I-1302J-30D01*
G01X252592Y197341D01*
X252055D01*
X252051Y197536D01*
G03X249447I-1302J-30D01*
G01X249443Y197341D01*
X248905D01*
X248901Y197536D01*
G03X246297I-1302J-30D01*
G01X246293Y197341D01*
X245756D01*
X245752Y197536D01*
G03X244450Y198808I-1302J-30D01*
G03X243606Y198498I-1J-1302D01*
G01X243257Y198847D01*
Y199149D01*
G02X243843Y199503I400J0D01*
G03X244450Y199353I607J1153D01*
G03Y201957I0J1302D01*
G03X243843Y201807I0J-1303D01*
G02X243257Y202161I-186J354D01*
G01Y204130D01*
X243721Y204594D01*
X245461D01*
X245506Y204550D01*
X245932D01*
G02X246324Y204069I0J-400D01*
G03X246297Y203805I1275J-264D01*
G03X248901I1302J0D01*
G03X248874Y204069I-1302J0D01*
G02X249266Y204550I392J81D01*
G01X249549D01*
Y204312D01*
X249536Y204277D01*
G03X249447Y203805I1213J-473D01*
G03X252051I1302J0D01*
G03X252024Y204069I-1302J0D01*
G02X252416Y204550I392J81D01*
G01X273721D01*
X293556Y224385D01*
Y238628D01*
X292017Y240167D01*
Y254638D01*
X292568Y255188D01*
X299800D01*
G03X300542Y255442I0J1211D01*
G37*
G36*
G01X275077Y359980D02*
X276740D01*
X278440Y358280D01*
Y354890D01*
X275140Y351590D01*
Y346130D01*
X269860Y340850D01*
Y325120D01*
X264610Y319870D01*
Y317718D01*
G02X264222Y317318I-400J0D01*
G03X262763Y315817I43J-1501D01*
G03X264219Y314316I1502J0D01*
G02X264607Y313915I-12J-400D01*
G01X264450Y269060D01*
X264063Y268673D01*
G02X263782Y268672I-141J142D01*
G03X262730Y269102I-1052J-1072D01*
G03X261228Y267600I0J-1502D01*
G03X261658Y266548I1502J0D01*
G02X261657Y266267I-143J-140D01*
G01X260337Y264947D01*
G03X259500Y265202I-837J-1246D01*
G03X257998Y263700I0J-1502D01*
G03X258253Y262863I1501J0D01*
G01X257300Y261910D01*
X256460D01*
X255400Y262970D01*
Y268280D01*
X257140Y270020D01*
Y270166D01*
X257620Y270645D01*
Y274869D01*
X257140Y275348D01*
Y278187D01*
X257317Y278208D01*
G03Y281192I-172J1492D01*
G01X257140Y281213D01*
Y283055D01*
G02X257637Y283443I400J0D01*
G03X258000Y283398I365J1457D01*
G03Y286402I0J1502D01*
G03X257637Y286357I2J-1502D01*
G02X257140Y286745I-97J388D01*
G01Y293262D01*
G02X257658Y293645I400J1D01*
G03X258100Y293578I444J1435D01*
G03Y296582I0J1502D01*
G03X257658Y296515I2J-1502D01*
G02X257140Y296898I-118J382D01*
G01Y310232D01*
G02X257616Y310625I400J0D01*
G03X257900Y310598I284J1475D01*
G03X259402Y312100I0J1502D01*
G03X258564Y313447I-1502J0D01*
G01X258534Y313462D01*
X257898Y314098D01*
X257142Y314855D01*
Y323836D01*
X264964Y331659D01*
G03X265052Y331756I-1000J996D01*
G01X265091Y331803D01*
G03X265409Y332558I-1086J902D01*
G01X265414Y332606D01*
G03X265422Y332752I-1404J150D01*
G01Y334839D01*
G03X265414Y334985I-1412J-4D01*
G01X265409Y335033D01*
G03X265100Y335778I-1404J-146D01*
G01X265065Y335821D01*
G03X264968Y335928I-1093J-893D01*
G01X264012Y336885D01*
Y351302D01*
X265502Y352792D01*
X265608Y352769D01*
G03X265922Y352736I313J1469D01*
G03X267424Y354238I0J1502D01*
G03X267391Y354552I-1502J1D01*
G01X267368Y354658D01*
X271098Y358388D01*
X272850D01*
G03X272996Y358396I-4J1412D01*
G01X273044Y358401D01*
G03X273799Y358719I-147J1404D01*
G01X273846Y358758D01*
G03X273943Y358846I-899J1088D01*
G01X275077Y359980D01*
G37*
G36*
G01X304193Y275375D02*
X305212D01*
X306888Y273698D01*
Y265202D01*
X299836Y258149D01*
X270053D01*
X265800Y262402D01*
Y266841D01*
G02X266284Y267232I400J0D01*
G03X266600Y267198I318J1468D01*
G03Y270202I0J1502D01*
G03X266284Y270168I2J-1502D01*
G02X265800Y270559I-84J391D01*
G01Y271078D01*
X270097Y275375D01*
X301181D01*
X301212Y275213D01*
G03X304162I1475J284D01*
G01X304193Y275375D01*
G37*
G36*
G01X287500Y384472D02*
X310844D01*
G02X311142Y383805I0J-400D01*
G03X310724Y382766I1084J-1040D01*
G03X313728I1502J0D01*
G03X313310Y383805I-1502J-1D01*
G02X313574Y384470I298J266D01*
G01X313943D01*
X316638Y381776D01*
Y368004D01*
G02X316009Y367676I-400J0D01*
G03X315075Y368002I-934J-1175D01*
G03X313816Y367318I0J-1501D01*
G02X313162Y367327I-324J235D01*
G03X311925Y367977I-1237J-852D01*
G03Y364973I0J-1502D01*
G03X313184Y365657I0J1501D01*
G02X313838Y365648I324J-235D01*
G03X315075Y364998I1237J852D01*
G03X316009Y365324I0J1501D01*
G02X316638Y364996I229J-328D01*
G01Y315727D01*
X312289Y311378D01*
Y294719D01*
X312116Y294696D01*
G03X311716Y294584I201J-1488D01*
G01X311708D01*
G02X311197Y294913I-115J383D01*
G03X309700Y296291I-1497J-124D01*
G03X308198Y294789I0J-1502D01*
G03X309687Y293287I1502J0D01*
G01X309701D01*
G03X310253Y293392I0J1502D01*
G01X310270Y293399D01*
G02X310818Y293083I152J-370D01*
G03X312116Y291718I1497J124D01*
G01X312289Y291695D01*
Y290141D01*
X312094Y289943D01*
X312018Y289938D01*
G03X310612Y288439I96J-1499D01*
G03X311140Y287295I1503J0D01*
G02X311157Y286714I-266J-299D01*
G01X310882Y286439D01*
X310863Y286427D01*
G03X310403Y285967I807J-1267D01*
G01X310391Y285948D01*
X310242Y285799D01*
X304702D01*
G02X304302Y286199I0J400D01*
G01Y286200D01*
G03X302800Y287702I-1502J0D01*
G03X302318Y287623I-1J-1502D01*
G01X302287Y287612D01*
X300099D01*
G03X299101Y287198I1J-1412D01*
G01X296850Y284946D01*
X295504Y283600D01*
X289330D01*
X287430Y285500D01*
X287982Y286052D01*
X288042Y286064D01*
G03X289257Y287538I-287J1474D01*
G03X287755Y289040I-1502J0D01*
G03X286281Y287825I0J-1502D01*
G01X286269Y287765D01*
X285717Y287213D01*
X282437Y290493D01*
Y307819D01*
G03Y309781I-1136J981D01*
G01Y362970D01*
G03X282438Y363026I-1210J50D01*
G01Y377100D01*
X282557Y377218D01*
G03X282590Y377253I-865J849D01*
G01X283037Y377700D01*
X285700D01*
X285874Y377874D01*
X286190Y377635D01*
G03X285998Y376900I1311J-735D01*
G03X287500Y378402I1502J0D01*
G03X286784Y378220I1J-1502D01*
G02X286200Y378575I-184J355D01*
G01Y383172D01*
X287500Y384472D01*
G37*
G36*
G01X295187Y461587D02*
X299678D01*
X300086Y461179D01*
Y448087D01*
X302598Y445575D01*
X329773D01*
X332404Y442944D01*
Y433340D01*
G03X332386Y432809I8235J-545D01*
G03X332404Y432278I8253J14D01*
G01Y427596D01*
X337355Y422645D01*
Y405966D01*
X336756Y405367D01*
X316533D01*
X314050Y407850D01*
Y430353D01*
X307981Y436422D01*
X296239D01*
X294749Y437912D01*
Y461149D01*
X295187Y461587D01*
G37*
G36*
G01X314745Y311552D02*
X340563D01*
X345848Y306266D01*
Y225640D01*
X345400Y225191D01*
X316790D01*
X315236Y226745D01*
Y243199D01*
X313353Y245082D01*
Y281064D01*
G03Y283150I-1081J1043D01*
G01Y287590D01*
G03Y289288I-1239J849D01*
G01Y292120D01*
G03Y294294I-1038J1087D01*
G01Y310160D01*
X314745Y311552D01*
G37*
G36*
G01X314385Y467812D02*
X315625D01*
X315966Y467471D01*
Y453751D01*
X315647Y453432D01*
X314431D01*
X313969Y453894D01*
Y467396D01*
X314385Y467812D01*
G37*
%LPC*%
G75*
G36*
G01X22813Y128943D02*
G03Y129573I-246J315D01*
G02X22234Y130758I923J1185D01*
G02X25238I1502J0D01*
G02X24659Y129573I-1502J0D01*
G03Y128943I246J-315D01*
G02X25238Y127758I-923J-1185D01*
G02X22234I-1502J0D01*
G02X22813Y128943I1502J0D01*
G37*
G36*
G01X31313D02*
G03Y129573I-246J315D01*
G02X30734Y130758I923J1185D01*
G02X33738I1502J0D01*
G02X33159Y129573I-1502J0D01*
G03Y128943I246J-315D01*
G02X33738Y127758I-923J-1185D01*
G02X30734I-1502J0D01*
G02X31313Y128943I1502J0D01*
G37*
G36*
G01X39813D02*
G03Y129573I-246J315D01*
G02X39234Y130758I923J1185D01*
G02X42238I1502J0D01*
G02X41659Y129573I-1502J0D01*
G03Y128943I246J-315D01*
G02X42238Y127758I-923J-1185D01*
G02X39234I-1502J0D01*
G02X39813Y128943I1502J0D01*
G37*
G36*
G01X38845Y212069D02*
G03X38824Y212658I-281J285D01*
G02X38298Y213800I977J1142D01*
G02X41302I1502J0D01*
G02X40855Y212731I-1502J0D01*
G03X40876Y212142I281J-285D01*
G02X41402Y211000I-977J-1142D01*
G02X38398I-1502J0D01*
G02X38845Y212069I1502J0D01*
G37*
G36*
G01X34677Y239385D02*
G03Y240015I-246J315D01*
G02X34098Y241200I923J1185D01*
G02X37102I1502J0D01*
G02X36523Y240015I-1502J0D01*
G03Y239385I246J-315D01*
G02X37102Y238200I-923J-1185D01*
G02X34098I-1502J0D01*
G02X34677Y239385I1502J0D01*
G37*
G36*
G01X38105Y302475D02*
G03Y303102I-249J314D01*
G02X37537Y304278I933J1176D01*
G02X40541I1502J0D01*
G02X39973Y303102I-1501J0D01*
G03Y302475I249J-313D01*
G02X40541Y301299I-933J-1176D01*
G02X37537I-1502J0D01*
G02X38105Y302475I1501J0D01*
G37*
G36*
G01X29956Y303264D02*
G02X29136Y304602I682J1338D01*
G02X32140I1502J0D01*
G02X31320Y303264I-1502J0D01*
G03Y302551I182J-357D01*
G02X32140Y301213I-682J-1338D01*
G02X29136I-1502J0D01*
G02X29956Y302551I1502J0D01*
G03Y303264I-182J356D01*
G37*
G36*
G01X21555Y303288D02*
G02X20735Y304626I682J1338D01*
G02X23739I1502J0D01*
G02X22919Y303288I-1502J0D01*
G03Y302575I182J-357D01*
G02X23739Y301237I-682J-1338D01*
G02X20735I-1502J0D01*
G02X21555Y302575I1502J0D01*
G03Y303288I-182J357D01*
G37*
G36*
G01X338620Y153254D02*
G03X338711Y153876I-199J347D01*
G02X338298Y154911I1090J1035D01*
G02X341302I1502J0D01*
G02X340549Y153609I-1502J0D01*
G03X340458Y152987I199J-347D01*
G02X340871Y151952I-1090J-1035D01*
G02X337867I-1502J0D01*
G02X338620Y153254I1502J0D01*
G37*
G36*
G01X338963Y164053D02*
G03X338934Y164684I-260J304D01*
G02X338298Y165911I866J1227D01*
G02X341302I1502J0D01*
G02X340776Y164769I-1503J0D01*
G03X340805Y164138I260J-304D01*
G02Y161684I-866J-1227D01*
G03X340776Y161053I231J-327D01*
G02X341302Y159911I-977J-1142D01*
G02X338298I-1502J0D01*
G02X338934Y161138I1502J0D01*
G03X338963Y161769I-231J327D01*
G02Y164053I977J1142D01*
G37*
G36*
G01X330273Y190898D02*
G03Y191424I-302J263D01*
G02X329903Y192411I1131J987D01*
G02X332907I1502J0D01*
G02X332537Y191424I-1501J0D01*
G03Y190898I302J-263D01*
G02Y188924I-1131J-987D01*
G03Y188398I302J-263D01*
G02X332907Y187411I-1131J-987D01*
G02X329903I-1502J0D01*
G02X330273Y188398I1501J0D01*
G03Y188924I-302J263D01*
G02Y190898I1131J987D01*
G37*
G36*
G01X318768Y199439D02*
G03X318672Y199959I-343J206D01*
G02X318099Y201140I929J1180D01*
G02X321103I1502J0D01*
G02X320887Y200364I-1502J0D01*
G03X320983Y199844I343J-206D01*
G02X321556Y198663I-929J-1180D01*
G02X318552I-1502J0D01*
G02X318768Y199439I1502J0D01*
G37*
G36*
G01X303752Y210950D02*
G03X303502Y211438I-384J111D01*
G02X302638Y212664I438J1226D01*
G02X305242I1302J0D01*
G02X305190Y212301I-1302J1D01*
G03X305440Y211813I384J-111D01*
G02X306304Y210587I-438J-1226D01*
G02X303700I-1302J0D01*
G02X303752Y210950I1302J-1D01*
G37*
G36*
G01X319819Y213842D02*
G03X319818Y214378I-297J267D01*
G02X319429Y215387I1114J1009D01*
G02X322433I1502J0D01*
G02X322049Y214384I-1502J0D01*
G03X322050Y213848I297J-267D01*
G02X322439Y212839I-1114J-1009D01*
G02X322081Y211866I-1501J0D01*
G03X322104Y211323I305J-259D01*
G02X322547Y210257I-1059J-1065D01*
G02X319543I-1502J0D01*
G02X319901Y211230I1501J0D01*
G03X319878Y211773I-305J259D01*
G02X319435Y212839I1059J1065D01*
G02X319819Y213842I1502J0D01*
G37*
G36*
G01X330273Y158924D02*
G02X329903Y159911I1131J987D01*
G02X332907I1502J0D01*
G02X332537Y158924I-1501J0D01*
G03Y158398I302J-263D01*
G02Y156424I-1131J-987D01*
G03Y155898I302J-263D01*
G02X332907Y154911I-1131J-987D01*
G02X331405Y153409I-1502J0D01*
G02X330972Y153473I1J1502D01*
G03X330468Y152999I-115J-383D01*
G02X330507Y152657I-1463J-340D01*
G02X329005Y154159I-1502J0D01*
G02X329438Y154095I-1J-1502D01*
G03X329942Y154569I115J383D01*
G02X329903Y154911I1463J340D01*
G02X330273Y155898I1501J0D01*
G03Y156424I-302J263D01*
G02Y158398I1131J987D01*
G03Y158924I-302J263D01*
G37*
G36*
G01X330489Y181736D02*
G02X329903Y182926I915J1190D01*
G02X332907I1502J0D01*
G02X332321Y181736I-1501J0D01*
G03Y181101I244J-317D01*
G02X332907Y179911I-915J-1190D01*
G02X332537Y178924I-1501J0D01*
G03Y178398I302J-263D01*
G02Y176424I-1131J-987D01*
G03Y175898I302J-263D01*
G02Y173924I-1131J-987D01*
G03Y173398I302J-263D01*
G02Y171424I-1131J-987D01*
G03Y170898I302J-263D01*
G02Y168924I-1131J-987D01*
G03Y168398I302J-263D01*
G02Y166424I-1131J-987D01*
G03Y165898I302J-263D01*
G02X332907Y164911I-1131J-987D01*
G02X329903I-1502J0D01*
G02X330273Y165898I1501J0D01*
G03Y166424I-302J263D01*
G02Y168398I1131J987D01*
G03Y168924I-302J263D01*
G02Y170898I1131J987D01*
G03Y171424I-302J263D01*
G02Y173398I1131J987D01*
G03Y173924I-302J263D01*
G02Y175898I1131J987D01*
G03Y176424I-302J263D01*
G02Y178398I1131J987D01*
G03Y178924I-302J263D01*
G02X329903Y179911I1131J987D01*
G02X330489Y181101I1501J0D01*
G03Y181736I-244J317D01*
G37*
G36*
G01X338869Y184732D02*
G02X338298Y185911I932J1179D01*
G02X341302I1502J0D01*
G02X340731Y184732I-1503J0D01*
G03Y184105I248J-314D01*
G02X341302Y182926I-932J-1179D01*
G02X340716Y181736I-1501J0D01*
G03Y181101I244J-317D01*
G02X341302Y179911I-915J-1190D01*
G02X340723Y178726I-1502J0D01*
G03Y178096I246J-315D01*
G02X341302Y176911I-923J-1185D01*
G02X338298I-1502J0D01*
G02X338877Y178096I1502J0D01*
G03Y178726I-246J315D01*
G02X338298Y179911I923J1185D01*
G02X338884Y181101I1501J0D01*
G03Y181736I-244J317D01*
G02X338298Y182926I915J1190D01*
G02X338869Y184105I1503J0D01*
G03Y184732I-248J313D01*
G37*
G36*
G01X296072Y196543D02*
G02X296070Y196616I1300J72D01*
G02X297372Y195314I1302J0D01*
G02X297171Y195330I2J1302D01*
G03X296710Y194912I-62J-395D01*
G02X296712Y194839I-1300J-72D01*
G02X295410Y196141I-1302J0D01*
G02X295611Y196125I-2J-1302D01*
G03X296072Y196543I62J395D01*
G37*
G36*
G01X291753Y196818D02*
G02X291059Y197970I609J1152D01*
G02X293663I1302J0D01*
G02X293002Y196836I-1303J0D01*
G03X293012Y196135I197J-348D01*
G02X293706Y194983I-609J-1152D01*
G02X291102I-1302J0D01*
G02X291763Y196117I1303J0D01*
G03X291753Y196818I-197J348D01*
G37*
G36*
G01X309367Y213244D02*
G02X308460Y212876I-907J934D01*
G02Y215480I0J1302D01*
G02X309617Y214775I0J-1302D01*
G03X310251Y214671I356J183D01*
G02X311158Y215039I907J-934D01*
G02Y212435I0J-1302D01*
G02X310001Y213140I0J1302D01*
G03X309367Y213244I-356J-183D01*
G37*
G36*
G01X205025Y256320D02*
G03X204877Y256933I-313J249D01*
G02X203998Y258300I623J1367D01*
G02X207002I1502J0D01*
G02X206675Y257365I-1502J1D01*
G03X206823Y256752I313J-249D01*
G02X207702Y255385I-623J-1367D01*
G02X204698I-1502J0D01*
G02X205025Y256320I1502J-1D01*
G37*
G36*
G01X238296Y236912D02*
G03X238587Y237369I-103J387D01*
G02X238568Y237596I1283J222D01*
G02X239870Y238898I1302J0D01*
G01X243019D01*
G02X244322Y237596I1J-1302D01*
G02X244265Y237217I-1303J2D01*
G03X244500Y236728I383J-117D01*
G02X245322Y235518I-480J-1210D01*
G02X242718I-1302J0D01*
G02X242750Y235805I1303J0D01*
G03X242360Y236294I-390J89D01*
G01X240315D01*
G03X239919Y235837I0J-400D01*
G02X239932Y235654I-1289J-184D01*
G02X237328I-1302J0D01*
G02X238296Y236912I1301J0D01*
G37*
G36*
G01X252130Y256047D02*
G03X252128Y256655I-261J303D01*
G02X251598Y257800I972J1145D01*
G02X254602I1502J0D01*
G02X254080Y256662I-1501J0D01*
G03X254082Y256054I261J-303D01*
G02X254612Y254909I-972J-1145D01*
G02X251608I-1502J0D01*
G02X252130Y256047I1501J0D01*
G37*
G36*
G01X241561Y270020D02*
G02X240585Y271427I526J1407D01*
G02X243589I1502J0D01*
G02X243286Y270523I-1502J1D01*
G03X243466Y269907I319J-241D01*
G02X244442Y268500I-526J-1407D01*
G02X241438I-1502J0D01*
G02X241741Y269404I1502J-1D01*
G03X241561Y270020I-319J241D01*
G37*
G36*
G01X215064Y254744D02*
G03X215336Y255215I-118J382D01*
G02X215298Y255550I1464J336D01*
G02X218302I1502J0D01*
G02X217246Y254116I-1502J0D01*
G03X216974Y253645I118J-382D01*
G02X217012Y253310I-1464J-336D01*
G02X214008I-1502J0D01*
G02X215064Y254744I1502J0D01*
G37*
G36*
G01X214446Y246041D02*
G02X213998Y247111I1054J1070D01*
G02X217002I1502J0D01*
G02X216238Y245803I-1502J0D01*
G03X216154Y245170I197J-348D01*
G02X216602Y244100I-1054J-1070D01*
G02X213598I-1502J0D01*
G02X214362Y245408I1502J0D01*
G03X214446Y246041I-197J348D01*
G37*
G36*
G01X300438Y228472D02*
G02X299618Y229810I682J1338D01*
G02X302622I1502J0D01*
G02X301802Y228472I-1502J0D01*
G03Y227759I182J-356D01*
G02X302622Y226421I-682J-1338D01*
G02X299618I-1502J0D01*
G02X300438Y227759I1502J0D01*
G03Y228472I-182J357D01*
G37*
G36*
G01X300272Y237526D02*
G02X299618Y238765I847J1239D01*
G02X302622I1502J0D01*
G02X301968Y237526I-1501J0D01*
G03Y236865I226J-331D01*
G02X302622Y235626I-847J-1239D01*
G02X299618I-1502J0D01*
G02X300272Y236865I1501J0D01*
G03Y237526I-226J330D01*
G37*
G36*
G01X286692Y364564D02*
G03X286700Y365137I-275J290D01*
G02X286259Y366200I1061J1063D01*
G02X289263I1502J0D01*
G02X288794Y365109I-1502J-1D01*
G03X288786Y364536I275J-290D01*
G02X289227Y363473I-1061J-1063D01*
G02X286223I-1502J0D01*
G02X286692Y364564I1502J1D01*
G37*
G36*
G01X304165Y308252D02*
G02X303000Y307698I-1165J948D01*
G02Y310702I0J1502D01*
G02X304362Y309832I0J-1501D01*
G03X305035Y309748I363J169D01*
G02X306200Y310302I1165J-948D01*
G02Y307298I0J-1502D01*
G02X304838Y308168I0J1501D01*
G03X304165Y308252I-363J-169D01*
G37*
G36*
G01X334042Y237331D02*
G02X333222Y238669I682J1338D01*
G02X334724Y240171I1502J0D01*
G02X336226Y238685I0J-1502D01*
G03X336803Y238331I400J5D01*
G02X337467Y238486I664J-1347D01*
G02Y235482I0J-1502D01*
G02X336803Y235637I0J1502D01*
G03X336226Y235278I-177J-359D01*
G02X334724Y233778I-1502J2D01*
G02X333222Y235280I0J1502D01*
G02X334042Y236618I1502J0D01*
G03Y237331I-182J357D01*
G37*
G36*
G01X325641Y237355D02*
G02X324821Y238693I682J1338D01*
G02X327825I1502J0D01*
G02X327005Y237355I-1502J0D01*
G03Y236642I182J-357D01*
G02X327825Y235304I-682J-1338D01*
G02X324821I-1502J0D01*
G02X325641Y236642I1502J0D01*
G03Y237355I-182J357D01*
G37*
G36*
G01X317240Y237379D02*
G02X316420Y238717I682J1338D01*
G02X319424I1502J0D01*
G02X318604Y237379I-1502J0D01*
G03Y236666I182J-357D01*
G02X319424Y235328I-682J-1338D01*
G02X316420I-1502J0D01*
G02X317240Y236666I1502J0D01*
G03Y237379I-182J357D01*
G37*
G54D16*
X39408Y195990D03*
X19100Y187420D03*
X24705Y258767D03*
X37485Y258807D03*
X41100Y248900D03*
X35700Y218000D03*
X78700Y340000D03*
X71700Y340600D03*
X86700Y119100D03*
X162200Y221376D03*
X339800Y169911D03*
Y189911D03*
X333278Y151129D03*
X323509Y153377D03*
X323384Y157378D03*
Y169378D03*
Y173378D03*
Y177378D03*
X278155Y176085D03*
X326932Y205685D03*
X326733Y209885D03*
X326731Y213648D03*
X337004Y202113D03*
Y206113D03*
Y210113D03*
X326733Y201485D03*
X320054Y195163D03*
X337083Y197000D03*
X339812Y173380D03*
X320239Y151075D03*
X323384Y165378D03*
X337400Y193449D03*
X323384Y161378D03*
X279457Y171318D03*
X237700Y257387D03*
X211265Y267300D03*
X196827Y240349D03*
X214034Y261482D03*
X252639Y247885D03*
X247689Y247929D03*
X237730Y248085D03*
X222833Y261668D03*
X223800Y254800D03*
X226405Y266335D03*
X299138Y244513D03*
X271100Y346575D03*
X262930Y325300D03*
X261500Y290440D03*
X262100Y280700D03*
X285911Y269899D03*
X281889D03*
X286372Y320700D03*
X308906Y362637D03*
X314340Y373296D03*
X308500Y382100D03*
X287507Y301596D03*
X303077Y297519D03*
X287050Y305850D03*
X295500Y354920D03*
X291300Y315900D03*
X312300Y340700D03*
X296780Y371500D03*
X296938Y325700D03*
X286372Y326768D03*
X289600Y322253D03*
X289939Y309060D03*
X290000Y335600D03*
X291000Y297700D03*
X290120Y339370D03*
X311000Y320500D03*
X306500Y301500D03*
X309500Y315000D03*
X301500Y326500D03*
X304000Y305000D03*
X300700Y341300D03*
X336461Y283202D03*
X327162Y278972D03*
X340612D03*
X339700Y293000D03*
G54D17*
X92360Y394175D03*
X100215Y381033D03*
X103383Y387350D03*
X100215Y387332D03*
X90766Y365322D03*
Y371584D03*
X81355Y374733D03*
Y362173D03*
X106514Y349574D03*
X106515Y352724D03*
X89210Y394175D03*
X87617Y390481D03*
X90766D03*
X68757Y359023D03*
Y365322D03*
Y371584D03*
Y377883D03*
Y374733D03*
Y362173D03*
X65607Y359023D03*
Y374733D03*
Y384182D03*
Y387332D03*
X71906Y371584D03*
X65607Y381033D03*
X68719D03*
X65607Y371584D03*
X97066Y349574D03*
X93916D03*
X90766D03*
X87617Y352724D03*
X90766D03*
X93916D03*
X81355Y349574D03*
X71906D03*
X78206D03*
X87617D03*
X75056D03*
X93916Y384182D03*
X81355Y381033D03*
Y384182D03*
X78206Y381033D03*
X90766D03*
Y384182D03*
X87617Y377883D03*
Y384182D03*
X181495Y229002D03*
X178346D03*
X181495Y225852D03*
X178346Y213254D03*
X184645Y206955D03*
Y210104D03*
X178346D03*
X181495Y219553D03*
Y222703D03*
Y206955D03*
X184645Y213254D03*
X181495Y216403D03*
X187794Y210104D03*
X175196Y203805D03*
X184645Y200655D03*
X190944D03*
X187794D03*
X178346Y203805D03*
X181495Y200655D03*
X175196Y206955D03*
X308008Y163487D03*
X314930Y171289D03*
X311158Y163487D03*
X308152Y169786D03*
X311158Y169643D03*
X308008Y166637D03*
X314307Y163487D03*
X314930Y168140D03*
X311158Y185534D03*
X311301Y182385D03*
X314930Y177588D03*
X308152Y172936D03*
Y176085D03*
Y182385D03*
X308008Y185391D03*
X308152Y179235D03*
X314930Y180738D03*
X314307Y185534D03*
X314930Y174439D03*
X314307Y191690D03*
X308008D03*
X311158D03*
X308008Y188540D03*
X311158D03*
X295410Y169786D03*
X305002D03*
Y172936D03*
X295410D03*
X292260Y169643D03*
Y163487D03*
X292404Y185534D03*
Y176085D03*
X305002D03*
X295410Y179235D03*
X292384Y172936D03*
X305002Y179235D03*
X295411Y185534D03*
X292260Y179235D03*
X292404Y191690D03*
X285980Y163487D03*
X289110D03*
X285482Y168102D03*
X286105Y172936D03*
Y182385D03*
X289254Y172792D03*
Y176085D03*
Y182385D03*
X282975Y172975D03*
X286105Y176085D03*
X289111Y179235D03*
X289254Y185534D03*
X286105D03*
X285482Y190187D03*
X289254Y191690D03*
X257048Y191244D03*
X231851D03*
X219290Y191207D03*
X228702Y191244D03*
X222402D03*
X311158Y204288D03*
X314307Y207438D03*
X308008D03*
X308152Y204432D03*
X311158Y210587D03*
X308008Y210731D03*
X314307Y204288D03*
Y210587D03*
Y213737D03*
X298714Y210477D03*
X305002Y204432D03*
X295410Y210587D03*
X219253Y203805D03*
X203542Y210104D03*
X212991Y206955D03*
X203542D03*
X212991Y203805D03*
X206692Y206955D03*
X209842D03*
X187794Y225852D03*
Y222703D03*
X200393Y210104D03*
Y206955D03*
Y213254D03*
X286105Y201139D03*
Y197989D03*
X289254Y194839D03*
X292404Y201282D03*
X289254Y201139D03*
Y197989D03*
X286105Y194839D03*
X299667Y201334D03*
X311158Y201139D03*
Y194839D03*
X308008Y198133D03*
X314307Y201139D03*
X311158Y197989D03*
X314307Y194839D03*
X308008D03*
X314307Y197989D03*
X203542Y200655D03*
X209842D03*
Y197506D03*
X212991D03*
Y200655D03*
X222402Y197506D03*
X219253D03*
Y200655D03*
X187794Y219553D03*
X225552Y197543D03*
X187794Y229002D03*
X212991Y232151D03*
X194094Y225852D03*
Y229002D03*
X197243D03*
X231851Y232151D03*
X241300D03*
X225590Y225852D03*
X228702Y229002D03*
X219253Y219553D03*
X222440Y222703D03*
X212991Y213254D03*
X203542Y219553D03*
X212991Y222740D03*
X203542Y222703D03*
X206692Y219553D03*
X219253Y229002D03*
X206692Y222703D03*
X209842D03*
X250749Y225852D03*
X257048Y225890D03*
X238150Y222703D03*
X231889Y222740D03*
X235038D03*
X228739Y216441D03*
X228702Y219553D03*
X253898Y222703D03*
X250749D03*
X231889Y219591D03*
X250749Y188095D03*
X253898Y184945D03*
X247599D03*
X250749D03*
X247599Y188095D03*
X244450D03*
X247599Y210104D03*
X250749D03*
X235001D03*
X289254Y213737D03*
X286105Y213721D03*
X253898Y200655D03*
X247599D03*
X250749D03*
X257048D03*
X286106Y210587D03*
G54D18*
X71000Y394400D03*
X273644Y174267D03*
X270472Y188488D03*
X264118Y188095D03*
X203542Y213254D03*
X301507Y195435D03*
%LPD*%
G75*
G54D10*
X-25100Y250316D03*
X-35100D03*
G54D11*
X3000Y8494D03*
Y28494D03*
Y48494D03*
Y68494D03*
Y88494D03*
Y108494D03*
Y128494D03*
Y148494D03*
Y168494D03*
Y188494D03*
Y208494D03*
Y228494D03*
Y248494D03*
Y268494D03*
Y288494D03*
Y308494D03*
Y342126D03*
Y362126D03*
Y382126D03*
Y402126D03*
Y422126D03*
Y442126D03*
X16626Y195848D03*
X19129D03*
Y193048D03*
X16626D03*
X19129Y204248D03*
X17000Y208017D03*
Y211541D03*
X16626Y198648D03*
Y201448D03*
X19129Y198648D03*
Y201448D03*
X16626Y204248D03*
X17000Y215713D03*
Y219288D03*
X18000Y240900D03*
Y237900D03*
Y249900D03*
Y246900D03*
Y243900D03*
X15688Y259063D03*
X13827Y325310D03*
X13869Y352239D03*
X14000Y401700D03*
Y406700D03*
X22218Y3000D03*
X23723Y123791D03*
Y120791D03*
X32223Y123791D03*
Y120791D03*
X31920Y186610D03*
X21250Y206220D03*
X21135Y236587D03*
X21205Y232767D03*
X21135Y240667D03*
Y243737D03*
X24690Y246467D03*
Y251967D03*
X21135Y246837D03*
X21035Y249937D03*
X24690Y249267D03*
X22237Y311481D03*
Y308592D03*
X30638Y311957D03*
Y309068D03*
X33000Y318700D03*
X23810Y322534D03*
X31300Y329900D03*
X29400Y430900D03*
X31500Y428500D03*
X20225Y447671D03*
X22692Y466518D03*
X42218Y3000D03*
X40723Y123791D03*
Y120791D03*
X49223Y123791D03*
Y121291D03*
X47294Y184491D03*
X36599Y189016D03*
X37360Y194050D03*
X37823Y198346D03*
X48035Y191535D03*
X47948Y201000D03*
X39567Y243133D03*
X40500Y236900D03*
X41574Y255937D03*
X46220Y277170D03*
X39039Y309044D03*
Y311933D03*
X50950Y318050D03*
X44525Y324000D03*
X44500Y351600D03*
X35101Y381610D03*
X42900Y412900D03*
X40848Y448440D03*
X62218Y3000D03*
X54200Y25400D03*
X52120Y78373D03*
X53400Y102788D03*
X52155Y121218D03*
X52410Y186900D03*
Y190190D03*
X60613Y312012D03*
X60600Y318000D03*
X64230Y303210D03*
X56600Y324300D03*
X52800Y322400D03*
X63000Y324100D03*
X58035Y370100D03*
X54400Y374700D03*
X59500Y394000D03*
X59511Y424477D03*
X54100Y448600D03*
X72044Y132312D03*
X71970Y135893D03*
X69195Y135799D03*
X69285Y132321D03*
X68335Y141369D03*
X68375Y144100D03*
X68434Y149506D03*
X68432Y152147D03*
X68960Y173300D03*
X72500Y214000D03*
X65755Y256045D03*
X68990Y260465D03*
X78600Y283970D03*
X75960Y284049D03*
X75870Y290700D03*
X75300Y305150D03*
X73400Y313700D03*
X77500Y316100D03*
X81000Y321900D03*
X76900Y323000D03*
X77592Y413437D03*
X69139Y413452D03*
X66319Y413492D03*
X67000Y408800D03*
X69700D03*
X71200Y431700D03*
X82218Y3000D03*
X92500Y116200D03*
X88500Y128000D03*
X89256Y135056D03*
X80300Y243700D03*
X81864Y297900D03*
X85600Y298100D03*
X90923Y293520D03*
X82200Y308700D03*
X82022Y303350D03*
X84126Y311790D03*
X79600Y312000D03*
X88565Y426535D03*
X102218Y3000D03*
X104600Y50501D03*
X108270Y138630D03*
X108551Y294241D03*
X105100Y309300D03*
X97800Y325700D03*
X103180Y336286D03*
X108108Y395100D03*
X109048Y425853D03*
X122218Y3000D03*
X125800Y47330D03*
X123710Y82300D03*
X118692Y137304D03*
X122900Y170100D03*
X112200Y234520D03*
X120200Y361600D03*
X114700Y348500D03*
X111869Y365454D03*
X116632Y411500D03*
X119500Y433600D03*
X140730Y72600D03*
X127600Y259700D03*
X126340Y382700D03*
X131540Y394690D03*
X133500Y409110D03*
X133070Y420874D03*
X134300Y416414D03*
X138750Y451500D03*
Y454500D03*
X142218Y3000D03*
X147600Y117000D03*
X146390Y224040D03*
X146000Y216350D03*
X141954Y224274D03*
X142300Y216300D03*
X145580Y248082D03*
X153419Y341978D03*
X151695Y357900D03*
X149500Y356700D03*
X139200Y372510D03*
X152200Y423100D03*
X148041Y426700D03*
X151398Y449930D03*
X162218Y3000D03*
X158246Y78872D03*
X156710Y73420D03*
X156200Y111600D03*
X159328Y160847D03*
X156481Y155933D03*
X162200Y158200D03*
X162653Y218843D03*
X159643Y226484D03*
X161200Y233600D03*
X156970Y255000D03*
X165013Y254986D03*
X160973D03*
X160590Y263300D03*
X156970Y263250D03*
X164800Y263300D03*
X161400Y307600D03*
X167008Y430718D03*
X165500Y433100D03*
X167865Y427771D03*
X159396Y449408D03*
X158100Y442700D03*
X168029Y456660D03*
X157500Y453390D03*
X182218Y3000D03*
X176300Y98700D03*
X182000Y117200D03*
X171600Y114000D03*
X182865Y113706D03*
X170867Y128211D03*
X178290Y128824D03*
X174553Y128728D03*
X168800Y126800D03*
X172100Y146300D03*
X176000Y140500D03*
X170800Y193100D03*
X172621Y208300D03*
X170400Y214700D03*
X174400Y254736D03*
Y251936D03*
X174292Y263300D03*
X171592Y263312D03*
X168710Y272256D03*
X168656Y275156D03*
X172530Y420950D03*
X184480Y429370D03*
X171400Y450600D03*
X187069Y116800D03*
X184729Y115820D03*
X187435Y129623D03*
X195983Y132294D03*
X186200Y125600D03*
X189700Y140400D03*
X196240Y253430D03*
X191408Y357451D03*
X190965Y348090D03*
X190370Y422490D03*
X195000Y422540D03*
X199940Y423700D03*
X189766Y432050D03*
X189838Y434910D03*
X186720Y432490D03*
X186300Y448700D03*
X185000Y451500D03*
X191780Y456700D03*
X202218Y3000D03*
X211400Y59238D03*
X204100Y67400D03*
X208200Y111760D03*
X212757Y127064D03*
X201100Y265120D03*
X208565Y404501D03*
X207539Y408686D03*
X205223Y422665D03*
X206150Y412821D03*
X222218Y3000D03*
X229900Y61000D03*
X224000Y74275D03*
X224958Y107236D03*
X226040Y101220D03*
X217262Y129294D03*
X225284Y132294D03*
X229342Y129240D03*
X217262Y132294D03*
X225300Y125200D03*
X227700Y151900D03*
X220866Y272160D03*
X229220Y283250D03*
X242218Y3000D03*
X239660Y91920D03*
X232325Y101230D03*
X236648Y100739D03*
X239900Y117550D03*
X233511Y129594D03*
X232384Y148884D03*
X233033Y266483D03*
X241263Y282654D03*
X234500Y293500D03*
X238400Y304200D03*
X235400Y303800D03*
X243010Y323400D03*
X233600Y377300D03*
X229900Y436600D03*
X236900Y440565D03*
X239500Y447750D03*
X235400Y451600D03*
X231250Y447000D03*
X235200Y449100D03*
X240200Y450650D03*
X236221Y454400D03*
X256900Y87300D03*
X251200Y93800D03*
X251900Y100100D03*
X258500Y146400D03*
X251354Y152877D03*
X256700Y263800D03*
X250288Y273581D03*
X251459Y286542D03*
Y283542D03*
X246514Y294325D03*
Y296825D03*
X257900Y312100D03*
X247923Y319000D03*
X253320Y323327D03*
X249400Y410300D03*
X257810Y435100D03*
X246700Y451500D03*
Y454100D03*
X262218Y3000D03*
X259894Y90072D03*
X265801Y106040D03*
X260970Y98600D03*
X269133Y164982D03*
X265226D03*
X268339Y222126D03*
X267100Y265000D03*
X269016Y266991D03*
X258000Y266300D03*
X262310Y311225D03*
X273580Y354250D03*
X274190Y408900D03*
X272400Y392400D03*
X269700Y411379D03*
X267100Y432900D03*
X263800Y430300D03*
X272999Y430500D03*
X271710Y449840D03*
X266727Y443185D03*
X261700Y439700D03*
X261100Y443500D03*
X282218Y3000D03*
X273400Y92800D03*
X276400Y92300D03*
X283500Y89500D03*
X278300Y95019D03*
X275386Y102710D03*
X285250Y117250D03*
X288280Y126212D03*
X279983Y235254D03*
X282483D03*
X280030Y267098D03*
Y264098D03*
X284357Y267027D03*
Y264027D03*
X287755Y287538D03*
X276660Y316900D03*
X273355Y330001D03*
X285860Y336131D03*
X277500Y348469D03*
X275520Y357910D03*
X277290Y355820D03*
X277572Y351198D03*
X285191Y390840D03*
X287630Y389378D03*
X277700Y406100D03*
X278900Y421400D03*
X277700Y412580D03*
X287500Y416100D03*
X275100Y427682D03*
X274619Y424725D03*
X283622Y447155D03*
X275138Y451215D03*
X276632Y439502D03*
X283674Y449975D03*
X283715Y452769D03*
X302218Y3000D03*
X294600Y106900D03*
X304000Y116500D03*
X294800Y111800D03*
X290200Y129500D03*
X298005Y151118D03*
Y148618D03*
Y146118D03*
X296734Y216079D03*
X290586Y234844D03*
X288086D03*
X291500Y287670D03*
Y285170D03*
X298840Y279640D03*
X292700Y403700D03*
X291703Y450819D03*
X295729Y453912D03*
Y456912D03*
Y459912D03*
X297738Y452418D03*
Y458418D03*
Y455418D03*
X307400Y122300D03*
X307560Y128500D03*
X307487Y219503D03*
X304987D03*
X310449Y218617D03*
X305000Y252400D03*
X307600Y252300D03*
X302800Y286200D03*
X302879Y282487D03*
X315810Y293450D03*
X317430Y295665D03*
X314820Y296128D03*
X314201Y302361D03*
X314180Y299440D03*
X314132Y310178D03*
X314170Y307020D03*
X308926Y401900D03*
X314969Y456527D03*
X322218Y3000D03*
X320500Y100400D03*
X318000Y117200D03*
X326323Y226349D03*
X317922Y226373D03*
X326323Y229738D03*
X317922Y229762D03*
X317670Y291430D03*
X325593Y406500D03*
X329093D03*
X318593D03*
X322093D03*
X331646Y466536D03*
X342218Y3000D03*
X342200Y100500D03*
X342180Y106900D03*
X334723Y226349D03*
Y229738D03*
X336312Y286352D03*
X339700Y295900D03*
X347100Y313700D03*
X342604Y318773D03*
X335475Y358500D03*
X335500Y380000D03*
X334112Y447668D03*
X351331Y20788D03*
Y40788D03*
Y60788D03*
Y80788D03*
Y100788D03*
Y120788D03*
Y140788D03*
Y160788D03*
Y180788D03*
Y200788D03*
Y220788D03*
Y240788D03*
Y260788D03*
Y280788D03*
Y300788D03*
X349290Y337646D03*
X351331Y357531D03*
Y377531D03*
Y397531D03*
Y417531D03*
Y437531D03*
G54D12*
G01X92500Y116200D02*
Y118700D01*
X93600Y119800D01*
Y127300D01*
X89256Y131644D01*
Y135056D01*
G01X208200Y111760D02*
Y108034D01*
X207324Y107158D01*
Y100824D01*
X196200Y89700D01*
X182300D01*
X177000Y84400D01*
X142536D01*
X142136Y84000D01*
X137700D01*
X133900Y87800D01*
X129210D01*
X123710Y82300D01*
X62458Y346425D03*
X71906Y352724D03*
X68757Y355873D03*
X78206Y374733D03*
Y362173D03*
Y365322D03*
Y371584D03*
X71906Y387332D03*
X71869Y381033D03*
X71906Y384182D03*
X90766Y374733D03*
Y362173D03*
X87617D03*
Y374733D03*
X106564Y346400D03*
X97066Y352724D03*
Y384182D03*
X166300Y212300D03*
X178346Y156599D03*
X181495Y159748D03*
X175196Y156599D03*
X181495D03*
X184645Y175496D03*
X181495Y169197D03*
X178346Y197506D03*
Y191244D03*
X181495D03*
X175196Y197506D03*
X174336Y192800D03*
X190944Y166047D03*
X187794Y156599D03*
Y172347D03*
Y169197D03*
X184645Y191244D03*
Y188095D03*
X190944Y210104D03*
Y213254D03*
X197243Y222703D03*
Y235301D03*
X212991Y162898D03*
X209842Y213254D03*
X200393Y225852D03*
X203542Y235301D03*
X222402Y156599D03*
X225552Y169197D03*
Y191244D03*
Y188095D03*
X238150Y156599D03*
X231851D03*
Y162898D03*
Y159748D03*
X238150D03*
X235001Y188095D03*
Y191244D03*
Y197506D03*
X241300Y188095D03*
X228702Y200655D03*
X235001Y203805D03*
X231851D03*
X228702D03*
X244450D03*
X247637Y225852D03*
G54D13*
G01X258040Y143900D02*
X263999D01*
X267393Y140506D01*
Y137734D01*
X268623Y136504D01*
X271395D01*
X271599Y136300D01*
X276337D01*
X277637Y135000D01*
X281200D01*
X288280Y127920D01*
Y126212D01*
G01X318000Y117200D02*
Y113300D01*
X319700Y111600D01*
X325200D01*
X327300Y113700D01*
Y124300D01*
X323449Y128151D01*
Y135329D01*
X317072Y141706D01*
X299074D01*
X296084Y144696D01*
X295852Y145256D01*
Y153128D01*
X291191Y157789D01*
X278736D01*
X274128Y162397D01*
X264740D01*
X263768Y163369D01*
G01X260034Y164703D02*
X264221Y160516D01*
X273193D01*
X277762Y155947D01*
X286756D01*
X288222Y154481D01*
Y151916D01*
X293254Y146884D01*
X294497Y143883D01*
X298299Y140081D01*
X306953D01*
X319600Y127434D01*
Y124366D01*
X307034Y111800D01*
X294800D01*
G01X260058Y161646D02*
X262800Y158904D01*
X271823D01*
X275801Y154926D01*
Y152113D01*
X279051Y148863D01*
X285043D01*
X289945Y143961D01*
Y141727D01*
X291278Y140394D01*
X294201D01*
X296195Y138400D01*
X306371D01*
X318000Y126771D01*
Y125029D01*
X306871Y113900D01*
X293701D01*
X292300Y112499D01*
Y107900D01*
X293300Y106900D01*
X294600D01*
G01X307560Y128500D02*
X305300D01*
X304500Y127700D01*
X298445D01*
X290694Y135451D01*
X286626D01*
X283877Y138200D01*
X279185D01*
X275367Y142018D01*
Y144475D01*
X271255Y148587D01*
X262214D01*
X261220Y149581D01*
G01X260446Y147867D02*
X261440Y146873D01*
X269638D01*
X272575Y143936D01*
Y142325D01*
X278300Y136600D01*
X283201D01*
X286108Y133693D01*
X289200D01*
X290200Y132693D01*
Y129500D01*
G01X307400Y122300D02*
X310100Y125000D01*
Y129900D01*
X307924Y132076D01*
X300289D01*
X297690Y134675D01*
X294161D01*
X291785Y137051D01*
X287289D01*
X284370Y139970D01*
X284142D01*
X284118Y139946D01*
X279898D01*
X277402Y142442D01*
Y144858D01*
X271047Y151213D01*
Y153737D01*
X269210Y155574D01*
X261126D01*
G01X261719Y157281D02*
X270850D01*
X273484Y154647D01*
Y151664D01*
X277911Y147237D01*
X282376D01*
X285429Y144184D01*
Y141174D01*
X287952Y138651D01*
X292465D01*
X294796Y136320D01*
X298351D01*
X300981Y133690D01*
X308573D01*
X311700Y130563D01*
Y120992D01*
X307208Y116500D01*
X304000D01*
G54D14*
G01X2010999Y-388000D02*
Y1475775D01*
X-407000D01*
Y-386798D01*
Y-755294D01*
Y-793716D01*
X-368578D01*
X1942346D01*
X2010999D01*
Y-725063D01*
Y-388000D01*
G01X-53307Y-609436D02*
Y-684436D01*
X446693D01*
Y-609436D01*
X-53307D01*
G01X-41307Y-674436D02*
Y-679436D01*
G01X-42764Y-674436D02*
X-39850D01*
G01X-34940Y-679436D02*
X-37474D01*
Y-674436D01*
X-34940D01*
G01X-35954Y-676853D02*
X-37474D01*
G01X-32374Y-674436D02*
Y-679436D01*
X-29840D01*
G01X-26007Y-679603D02*
X-26134Y-679519D01*
Y-679353D01*
X-26007Y-679269D01*
X-25880Y-679353D01*
Y-679519D01*
X-26007Y-679603D01*
G01Y-677353D02*
X-26134Y-677269D01*
Y-677103D01*
X-26007Y-677019D01*
X-25880Y-677103D01*
Y-677269D01*
X-26007Y-677353D01*
G01X-21224Y-681103D02*
X-21857Y-680269D01*
X-22174Y-679436D01*
Y-676103D01*
X-21857Y-675269D01*
X-21224Y-674436D01*
G01X-15807D02*
X-16314Y-674603D01*
X-16694Y-675019D01*
X-16947Y-675519D01*
X-17137Y-676186D01*
X-17200Y-676936D01*
X-17137Y-677686D01*
X-16947Y-678353D01*
X-16694Y-678853D01*
X-16314Y-679269D01*
X-15807Y-679436D01*
X-15300Y-679269D01*
X-14920Y-678853D01*
X-14667Y-678353D01*
X-14477Y-677686D01*
X-14414Y-676936D01*
X-14477Y-676186D01*
X-14667Y-675519D01*
X-14920Y-675019D01*
X-15300Y-674603D01*
X-15807Y-674436D01*
G01X-12100Y-678436D02*
X-11720Y-679019D01*
X-11214Y-679353D01*
X-10644Y-679436D01*
X-10137Y-679353D01*
X-9630Y-678936D01*
X-9314Y-678436D01*
X-9250Y-677936D01*
X-9377Y-677353D01*
X-9820Y-676936D01*
X-10264Y-676769D01*
X-10834D01*
G01X-10264D02*
X-9884Y-676519D01*
X-9567Y-676103D01*
X-9440Y-675603D01*
X-9567Y-675103D01*
X-9884Y-674686D01*
X-10454Y-674436D01*
X-11024Y-674519D01*
X-11594Y-674853D01*
G01X-5290Y-681103D02*
X-4657Y-680269D01*
X-4340Y-679436D01*
Y-676103D01*
X-4657Y-675269D01*
X-5290Y-674436D01*
G01X-1900Y-678436D02*
X-1520Y-679019D01*
X-1014Y-679353D01*
X-444Y-679436D01*
X63Y-679353D01*
X570Y-678936D01*
X886Y-678436D01*
X950Y-677936D01*
X823Y-677353D01*
X380Y-676936D01*
X-64Y-676769D01*
X-634D01*
G01X-64D02*
X316Y-676519D01*
X633Y-676103D01*
X760Y-675603D01*
X633Y-675103D01*
X316Y-674686D01*
X-254Y-674436D01*
X-824Y-674519D01*
X-1394Y-674853D01*
G01X3390Y-675269D02*
X3770Y-674769D01*
X4213Y-674519D01*
X4720Y-674436D01*
X5353Y-674603D01*
X5796Y-675019D01*
X5923Y-675519D01*
X5860Y-676019D01*
X5606Y-676436D01*
X4340Y-677269D01*
X3770Y-677853D01*
X3390Y-678686D01*
X3263Y-679436D01*
X5923D01*
G01X9566D02*
X9693Y-678353D01*
X9883Y-677436D01*
X10136Y-676603D01*
X10453Y-675686D01*
X10960Y-674436D01*
X8426D01*
G01X13970Y-677769D02*
X15616D01*
G01X18690Y-675269D02*
X19070Y-674769D01*
X19513Y-674519D01*
X20020Y-674436D01*
X20653Y-674603D01*
X21096Y-675019D01*
X21223Y-675519D01*
X21160Y-676019D01*
X20906Y-676436D01*
X19640Y-677269D01*
X19070Y-677853D01*
X18690Y-678686D01*
X18563Y-679436D01*
X21223D01*
G01X23600Y-678436D02*
X23980Y-679019D01*
X24486Y-679353D01*
X25056Y-679436D01*
X25563Y-679353D01*
X26070Y-678936D01*
X26386Y-678436D01*
X26450Y-677936D01*
X26323Y-677353D01*
X25880Y-676936D01*
X25436Y-676769D01*
X24866D01*
G01X25436D02*
X25816Y-676519D01*
X26133Y-676103D01*
X26260Y-675603D01*
X26133Y-675103D01*
X25816Y-674686D01*
X25246Y-674436D01*
X24676Y-674519D01*
X24106Y-674853D01*
G01X30853Y-679436D02*
Y-674436D01*
X28510Y-678019D01*
X31676D01*
G01X33800Y-678686D02*
X34180Y-679103D01*
X34623Y-679353D01*
X35193Y-679436D01*
X35763Y-679269D01*
X36206Y-678936D01*
X36523Y-678353D01*
X36586Y-677686D01*
X36460Y-677019D01*
X36143Y-676603D01*
X35700Y-676269D01*
X35256Y-676186D01*
X34813Y-676269D01*
X34243Y-676603D01*
X34433Y-674436D01*
X36143D01*
G01X44190Y-679436D02*
Y-674436D01*
X46596D01*
G01X45710Y-676853D02*
X44190D01*
G01X48910Y-679436D02*
X50493Y-674436D01*
X52076Y-679436D01*
G01X51506Y-677686D02*
X49480D01*
G01X54263Y-679436D02*
X56923Y-674436D01*
G01X54263D02*
X56923Y-679436D01*
G01X60693Y-679603D02*
X60566Y-679519D01*
Y-679353D01*
X60693Y-679269D01*
X60820Y-679353D01*
Y-679519D01*
X60693Y-679603D01*
G01Y-677353D02*
X60566Y-677269D01*
Y-677103D01*
X60693Y-677019D01*
X60820Y-677103D01*
Y-677269D01*
X60693Y-677353D01*
G01X65476Y-681103D02*
X64843Y-680269D01*
X64526Y-679436D01*
Y-676103D01*
X64843Y-675269D01*
X65476Y-674436D01*
G01X70893D02*
X70386Y-674603D01*
X70006Y-675019D01*
X69753Y-675519D01*
X69563Y-676186D01*
X69500Y-676936D01*
X69563Y-677686D01*
X69753Y-678353D01*
X70006Y-678853D01*
X70386Y-679269D01*
X70893Y-679436D01*
X71400Y-679269D01*
X71780Y-678853D01*
X72033Y-678353D01*
X72223Y-677686D01*
X72286Y-676936D01*
X72223Y-676186D01*
X72033Y-675519D01*
X71780Y-675019D01*
X71400Y-674603D01*
X70893Y-674436D01*
G01X74600Y-678436D02*
X74980Y-679019D01*
X75486Y-679353D01*
X76056Y-679436D01*
X76563Y-679353D01*
X77070Y-678936D01*
X77386Y-678436D01*
X77450Y-677936D01*
X77323Y-677353D01*
X76880Y-676936D01*
X76436Y-676769D01*
X75866D01*
G01X76436D02*
X76816Y-676519D01*
X77133Y-676103D01*
X77260Y-675603D01*
X77133Y-675103D01*
X76816Y-674686D01*
X76246Y-674436D01*
X75676Y-674519D01*
X75106Y-674853D01*
G01X81410Y-681103D02*
X82043Y-680269D01*
X82360Y-679436D01*
Y-676103D01*
X82043Y-675269D01*
X81410Y-674436D01*
G01X84800Y-678436D02*
X85180Y-679019D01*
X85686Y-679353D01*
X86256Y-679436D01*
X86763Y-679353D01*
X87270Y-678936D01*
X87586Y-678436D01*
X87650Y-677936D01*
X87523Y-677353D01*
X87080Y-676936D01*
X86636Y-676769D01*
X86066D01*
G01X86636D02*
X87016Y-676519D01*
X87333Y-676103D01*
X87460Y-675603D01*
X87333Y-675103D01*
X87016Y-674686D01*
X86446Y-674436D01*
X85876Y-674519D01*
X85306Y-674853D01*
G01X90216Y-678853D02*
X90660Y-679269D01*
X91166Y-679436D01*
X91673Y-679269D01*
X92116Y-678769D01*
X92433Y-678019D01*
X92560Y-677269D01*
Y-676353D01*
X92433Y-675603D01*
X92116Y-674936D01*
X91736Y-674603D01*
X91293Y-674436D01*
X90786Y-674603D01*
X90406Y-674936D01*
X90153Y-675436D01*
X90026Y-676103D01*
X90153Y-676686D01*
X90470Y-677269D01*
X90850Y-677603D01*
X91293Y-677686D01*
X91800Y-677519D01*
X92180Y-677103D01*
X92560Y-676353D01*
G01X96266Y-679436D02*
X96393Y-678353D01*
X96583Y-677436D01*
X96836Y-676603D01*
X97153Y-675686D01*
X97660Y-674436D01*
X95126D01*
G01X100670Y-677769D02*
X102316D01*
G01X105200Y-678436D02*
X105580Y-679019D01*
X106086Y-679353D01*
X106656Y-679436D01*
X107163Y-679353D01*
X107670Y-678936D01*
X107986Y-678436D01*
X108050Y-677936D01*
X107923Y-677353D01*
X107480Y-676936D01*
X107036Y-676769D01*
X106466D01*
G01X107036D02*
X107416Y-676519D01*
X107733Y-676103D01*
X107860Y-675603D01*
X107733Y-675103D01*
X107416Y-674686D01*
X106846Y-674436D01*
X106276Y-674519D01*
X105706Y-674853D01*
G01X110490Y-677353D02*
X110933Y-676769D01*
X111313Y-676436D01*
X111820Y-676269D01*
X112263Y-676436D01*
X112580Y-676769D01*
X112833Y-677269D01*
X112896Y-677853D01*
X112833Y-678353D01*
X112580Y-678853D01*
X112200Y-679269D01*
X111756Y-679436D01*
X111250Y-679269D01*
X110806Y-678769D01*
X110553Y-678019D01*
X110490Y-677186D01*
X110616Y-676103D01*
X110806Y-675519D01*
X111123Y-674936D01*
X111566Y-674519D01*
X112010Y-674436D01*
X112453Y-674603D01*
X112770Y-675019D01*
G01X116793Y-679436D02*
Y-674436D01*
X116033Y-675436D01*
G01Y-679436D02*
X117553D01*
G01X122653D02*
Y-674436D01*
X120310Y-678019D01*
X123476D01*
G01X141693Y-609436D02*
Y-684436D01*
G01Y-659436D02*
X244693D01*
Y-634436D01*
G01X141693D02*
X244693D01*
G01X246693Y-609436D02*
Y-684436D01*
G01X244693Y-609436D02*
Y-684436D01*
G01X252200Y-669436D02*
Y-664436D01*
X253466D01*
X253973Y-664686D01*
X254353Y-665019D01*
X254670Y-665519D01*
X254923Y-666103D01*
X254986Y-666936D01*
X254923Y-667769D01*
X254670Y-668353D01*
X254353Y-668853D01*
X253973Y-669186D01*
X253466Y-669436D01*
X252200D01*
G01X257110D02*
X258693Y-664436D01*
X260276Y-669436D01*
G01X259706Y-667686D02*
X257680D01*
G01X263793Y-664436D02*
Y-669436D01*
G01X262336Y-664436D02*
X265250D01*
G01X270160Y-669436D02*
X267626D01*
Y-664436D01*
X270160D01*
G01X269146Y-666853D02*
X267626D01*
G01X273993Y-669603D02*
X273866Y-669519D01*
Y-669353D01*
X273993Y-669269D01*
X274120Y-669353D01*
Y-669519D01*
X273993Y-669603D01*
G01Y-667353D02*
X273866Y-667269D01*
Y-667103D01*
X273993Y-667019D01*
X274120Y-667103D01*
Y-667269D01*
X273993Y-667353D01*
G01X246693Y-659436D02*
X446693D01*
G01X252326Y-644436D02*
Y-639436D01*
X253846D01*
X254353Y-639686D01*
X254733Y-640269D01*
X254860Y-640936D01*
X254733Y-641603D01*
X254416Y-642103D01*
X253846Y-642353D01*
X252326D01*
G01X257553Y-644603D02*
X259833Y-639436D01*
G01X262336Y-644436D02*
Y-639436D01*
X265250Y-644436D01*
Y-639436D01*
G01X268893Y-644603D02*
X268766Y-644519D01*
Y-644353D01*
X268893Y-644269D01*
X269020Y-644353D01*
Y-644519D01*
X268893Y-644603D01*
G01Y-642353D02*
X268766Y-642269D01*
Y-642103D01*
X268893Y-642019D01*
X269020Y-642103D01*
Y-642269D01*
X268893Y-642353D01*
G01X246693Y-634436D02*
X446693D01*
G01X252326Y-619436D02*
Y-614436D01*
X253846D01*
X254353Y-614686D01*
X254733Y-615269D01*
X254860Y-615936D01*
X254733Y-616603D01*
X254416Y-617103D01*
X253846Y-617353D01*
X252326D01*
G01X257426Y-619436D02*
Y-614436D01*
X259010D01*
X259516Y-614686D01*
X259833Y-615019D01*
X259960Y-615686D01*
X259833Y-616353D01*
X259453Y-616769D01*
X259010Y-617019D01*
X257426D01*
G01X259010D02*
X259960Y-619436D01*
G01X263793D02*
X263286Y-619353D01*
X262843Y-619019D01*
X262463Y-618519D01*
X262210Y-617936D01*
X262083Y-617269D01*
Y-616603D01*
X262210Y-615936D01*
X262463Y-615353D01*
X262843Y-614853D01*
X263286Y-614519D01*
X263793Y-614436D01*
X264300Y-614519D01*
X264743Y-614853D01*
X265123Y-615353D01*
X265376Y-615936D01*
X265503Y-616603D01*
Y-617269D01*
X265376Y-617936D01*
X265123Y-618519D01*
X264743Y-619019D01*
X264300Y-619353D01*
X263793Y-619436D01*
G01X267626Y-618436D02*
X267943Y-618936D01*
X268323Y-619269D01*
X268766Y-619436D01*
X269273Y-619269D01*
X269653Y-618936D01*
X270033Y-618436D01*
X270160Y-617769D01*
Y-614436D01*
G01X275260Y-619436D02*
X272726D01*
Y-614436D01*
X275260D01*
G01X274246Y-616853D02*
X272726D01*
G01X280486Y-614853D02*
X280106Y-614603D01*
X279663Y-614436D01*
X279156D01*
X278586Y-614686D01*
X278143Y-615103D01*
X277826Y-615603D01*
X277573Y-616436D01*
X277510Y-617186D01*
X277636Y-617936D01*
X277826Y-618436D01*
X278206Y-618936D01*
X278650Y-619269D01*
X279093Y-619436D01*
X279536D01*
X279980Y-619269D01*
X280360Y-619019D01*
X280676Y-618686D01*
G01X284193Y-614436D02*
Y-619436D01*
G01X282736Y-614436D02*
X285650D01*
G01X289293Y-619603D02*
X289166Y-619519D01*
Y-619353D01*
X289293Y-619269D01*
X289420Y-619353D01*
Y-619519D01*
X289293Y-619603D01*
G01Y-617353D02*
X289166Y-617269D01*
Y-617103D01*
X289293Y-617019D01*
X289420Y-617103D01*
Y-617269D01*
X289293Y-617353D01*
G01X361693Y-659436D02*
Y-684436D01*
G01X364326Y-661936D02*
Y-666936D01*
X366860D01*
G01X369933Y-661936D02*
X371453D01*
G01X370693D02*
Y-666936D01*
G01X369933D02*
X371453D01*
G01X376300Y-664269D02*
X376553Y-664019D01*
X376743Y-663603D01*
X376870Y-663019D01*
X376743Y-662519D01*
X376490Y-662186D01*
X376046Y-661936D01*
X374336D01*
Y-666936D01*
X376426D01*
X376870Y-666603D01*
X377123Y-666103D01*
X377250Y-665519D01*
X377123Y-664936D01*
X376743Y-664436D01*
X376300Y-664269D01*
X374336D01*
G01X380893Y-667103D02*
X380766Y-667019D01*
Y-666853D01*
X380893Y-666769D01*
X381020Y-666853D01*
Y-667019D01*
X380893Y-667103D01*
G01Y-664853D02*
X380766Y-664769D01*
Y-664603D01*
X380893Y-664519D01*
X381020Y-664603D01*
Y-664769D01*
X380893Y-664853D01*
G01X404693Y-659436D02*
Y-684436D01*
G01Y-634436D02*
Y-659436D01*
G01X412706Y-687603D02*
X412813Y-687478D01*
X412893Y-687269D01*
X412946Y-686978D01*
X412893Y-686728D01*
X412786Y-686561D01*
X412600Y-686436D01*
X411880D01*
Y-688936D01*
X412760D01*
X412946Y-688769D01*
X413053Y-688519D01*
X413106Y-688228D01*
X413053Y-687936D01*
X412893Y-687686D01*
X412706Y-687603D01*
X411880D01*
G01X415173Y-688936D02*
Y-687269D01*
G01Y-687561D02*
X415066Y-687394D01*
X414906Y-687311D01*
X414720Y-687269D01*
X414533Y-687353D01*
X414373Y-687519D01*
X414266Y-687769D01*
X414213Y-688103D01*
X414266Y-688436D01*
X414373Y-688686D01*
X414533Y-688853D01*
X414720Y-688936D01*
X414906Y-688894D01*
X415066Y-688769D01*
X415173Y-688603D01*
G01X416493Y-688644D02*
X416626Y-688811D01*
X416813Y-688936D01*
X416973D01*
X417133Y-688853D01*
X417240Y-688728D01*
X417293Y-688561D01*
X417266Y-688311D01*
X417160Y-688186D01*
X416680Y-687936D01*
X416573Y-687644D01*
X416626Y-687436D01*
X416733Y-687311D01*
X416893Y-687269D01*
X417053Y-687311D01*
X417213Y-687436D01*
G01X418693Y-687811D02*
X419546D01*
X419466Y-687519D01*
X419333Y-687353D01*
X419146Y-687269D01*
X418960Y-687311D01*
X418800Y-687436D01*
X418693Y-687728D01*
X418640Y-687978D01*
Y-688228D01*
X418693Y-688478D01*
X418826Y-688728D01*
X418986Y-688894D01*
X419173Y-688936D01*
X419360Y-688853D01*
X419546Y-688603D01*
G01X420813Y-688936D02*
Y-686436D01*
G01Y-687686D02*
X420946Y-687436D01*
X421106Y-687311D01*
X421266Y-687269D01*
X421506Y-687353D01*
X421666Y-687519D01*
X421773Y-687811D01*
Y-688144D01*
X421720Y-688478D01*
X421613Y-688728D01*
X421426Y-688894D01*
X421266Y-688936D01*
X421106Y-688894D01*
X420946Y-688769D01*
X420813Y-688561D01*
G01X423493Y-688936D02*
X423333Y-688894D01*
X423173Y-688728D01*
X423066Y-688436D01*
X423013Y-688103D01*
X423066Y-687769D01*
X423173Y-687478D01*
X423333Y-687311D01*
X423493Y-687269D01*
X423653Y-687311D01*
X423813Y-687478D01*
X423920Y-687769D01*
X423946Y-688103D01*
X423920Y-688436D01*
X423813Y-688728D01*
X423653Y-688894D01*
X423493Y-688936D01*
G01X426173D02*
Y-687269D01*
G01Y-687561D02*
X426066Y-687394D01*
X425906Y-687311D01*
X425720Y-687269D01*
X425533Y-687353D01*
X425373Y-687519D01*
X425266Y-687769D01*
X425213Y-688103D01*
X425266Y-688436D01*
X425373Y-688686D01*
X425533Y-688853D01*
X425720Y-688936D01*
X425906Y-688894D01*
X426066Y-688769D01*
X426173Y-688603D01*
G01X427520Y-688936D02*
Y-687269D01*
G01Y-687603D02*
X427653Y-687436D01*
X427786Y-687311D01*
X427973Y-687269D01*
X428106Y-687311D01*
X428266Y-687436D01*
G01X430573Y-686436D02*
Y-688936D01*
G01Y-688561D02*
X430466Y-688769D01*
X430306Y-688894D01*
X430120Y-688936D01*
X429906Y-688853D01*
X429746Y-688644D01*
X429640Y-688394D01*
X429613Y-688103D01*
X429640Y-687811D01*
X429746Y-687561D01*
X429906Y-687353D01*
X430120Y-687269D01*
X430306Y-687311D01*
X430440Y-687394D01*
X430573Y-687561D01*
G01X433960Y-688936D02*
Y-686436D01*
X434626D01*
X434840Y-686561D01*
X434973Y-686728D01*
X435026Y-687061D01*
X434973Y-687394D01*
X434813Y-687603D01*
X434626Y-687728D01*
X433960D01*
G01X434626D02*
X435026Y-688936D01*
G01X436293Y-687811D02*
X437146D01*
X437066Y-687519D01*
X436933Y-687353D01*
X436746Y-687269D01*
X436560Y-687311D01*
X436400Y-687436D01*
X436293Y-687728D01*
X436240Y-687978D01*
Y-688228D01*
X436293Y-688478D01*
X436426Y-688728D01*
X436586Y-688894D01*
X436773Y-688936D01*
X436960Y-688853D01*
X437146Y-688603D01*
G01X438413Y-687269D02*
X438893Y-688936D01*
X439373Y-687269D01*
G01X441093Y-689019D02*
X441040Y-688978D01*
Y-688894D01*
X441093Y-688853D01*
X441146Y-688894D01*
Y-688978D01*
X441093Y-689019D01*
G01X443613Y-688936D02*
Y-686436D01*
X442626Y-688228D01*
X443960D01*
G01X444826Y-688936D02*
X445493Y-686436D01*
X446160Y-688936D01*
G01X445920Y-688061D02*
X445066D01*
G01X408593Y-661936D02*
Y-666936D01*
G01X407136Y-661936D02*
X410050D01*
G01X413693Y-666936D02*
X413313Y-666853D01*
X412933Y-666519D01*
X412680Y-665936D01*
X412553Y-665269D01*
X412680Y-664603D01*
X412933Y-664019D01*
X413313Y-663686D01*
X413693Y-663603D01*
X414073Y-663686D01*
X414453Y-664019D01*
X414706Y-664603D01*
X414770Y-665269D01*
X414706Y-665936D01*
X414453Y-666519D01*
X414073Y-666853D01*
X413693Y-666936D01*
G01X418793D02*
X418413Y-666853D01*
X418033Y-666519D01*
X417780Y-665936D01*
X417653Y-665269D01*
X417780Y-664603D01*
X418033Y-664019D01*
X418413Y-663686D01*
X418793Y-663603D01*
X419173Y-663686D01*
X419553Y-664019D01*
X419806Y-664603D01*
X419870Y-665269D01*
X419806Y-665936D01*
X419553Y-666519D01*
X419173Y-666853D01*
X418793Y-666936D01*
G01X423893D02*
Y-661936D01*
G01X428993Y-667103D02*
X428866Y-667019D01*
Y-666853D01*
X428993Y-666769D01*
X429120Y-666853D01*
Y-667019D01*
X428993Y-667103D01*
G01Y-664853D02*
X428866Y-664769D01*
Y-664603D01*
X428993Y-664519D01*
X429120Y-664603D01*
Y-664769D01*
X428993Y-664853D01*
G01X407326Y-641936D02*
Y-636936D01*
X408910D01*
X409416Y-637186D01*
X409733Y-637519D01*
X409860Y-638186D01*
X409733Y-638853D01*
X409353Y-639269D01*
X408910Y-639519D01*
X407326D01*
G01X408910D02*
X409860Y-641936D01*
G01X414960D02*
X412426D01*
Y-636936D01*
X414960D01*
G01X413946Y-639353D02*
X412426D01*
G01X417210Y-636936D02*
X418793Y-641936D01*
X420376Y-636936D01*
G01X423893Y-642103D02*
X423766Y-642019D01*
Y-641853D01*
X423893Y-641769D01*
X424020Y-641853D01*
Y-642019D01*
X423893Y-642103D01*
G01Y-639853D02*
X423766Y-639769D01*
Y-639603D01*
X423893Y-639519D01*
X424020Y-639603D01*
Y-639769D01*
X423893Y-639853D01*
G01X2010999Y-388000D02*
Y1475775D01*
X-407000D01*
Y-386798D01*
Y-755294D01*
Y-793716D01*
X-368578D01*
X1942346D01*
X2010999D01*
Y-725063D01*
Y-388000D01*
G01X-42602Y-671096D02*
X-41975Y-671621D01*
X-41270Y-671936D01*
X-40644D01*
X-40017Y-671621D01*
X-39547Y-671096D01*
X-39312Y-670361D01*
X-39469Y-669626D01*
X-39860Y-668996D01*
X-40565Y-668576D01*
X-41505Y-668366D01*
X-42054Y-667946D01*
X-42289Y-667211D01*
X-42132Y-666476D01*
X-41740Y-665951D01*
X-41192Y-665636D01*
X-40644D01*
X-40095Y-665846D01*
X-39625Y-666371D01*
G01X-36302Y-671936D02*
Y-665636D01*
G01X-33012D02*
Y-671936D01*
G01Y-668786D02*
X-36302D01*
G01X-29297Y-665636D02*
X-27417D01*
G01X-28357D02*
Y-671936D01*
G01X-29297D02*
X-27417D01*
G01X-20490D02*
X-23624D01*
Y-665636D01*
X-20490D01*
G01X-21744Y-668681D02*
X-23624D01*
G01X-17559Y-671936D02*
Y-665636D01*
X-13955Y-671936D01*
Y-665636D01*
G01X-9614Y-673091D02*
X-9300Y-671726D01*
G01X-3157Y-665636D02*
Y-671936D01*
G01X-4959Y-665636D02*
X-1355D01*
G01X1185Y-671936D02*
X3143Y-665636D01*
X5101Y-671936D01*
G01X4396Y-669731D02*
X1890D01*
G01X8503Y-665636D02*
X10383D01*
G01X9443D02*
Y-671936D01*
G01X8503D02*
X10383D01*
G01X13393Y-665636D02*
X14490Y-671936D01*
X15743Y-665636D01*
X16996Y-671936D01*
X18093Y-665636D01*
G01X20085Y-671936D02*
X22043Y-665636D01*
X24001Y-671936D01*
G01X23296Y-669731D02*
X20790D01*
G01X26541Y-671936D02*
Y-665636D01*
X30145Y-671936D01*
Y-665636D01*
G01X39376Y-671936D02*
Y-665636D01*
X41335D01*
X41961Y-665951D01*
X42353Y-666371D01*
X42510Y-667211D01*
X42353Y-668051D01*
X41883Y-668576D01*
X41335Y-668891D01*
X39376D01*
G01X41335D02*
X42510Y-671936D01*
G01X47243Y-672146D02*
X47086Y-672041D01*
Y-671831D01*
X47243Y-671726D01*
X47400Y-671831D01*
Y-672041D01*
X47243Y-672146D01*
G01X53543Y-671936D02*
X52916Y-671831D01*
X52368Y-671411D01*
X51898Y-670781D01*
X51585Y-670046D01*
X51428Y-669206D01*
Y-668366D01*
X51585Y-667526D01*
X51898Y-666791D01*
X52368Y-666161D01*
X52916Y-665741D01*
X53543Y-665636D01*
X54170Y-665741D01*
X54718Y-666161D01*
X55188Y-666791D01*
X55501Y-667526D01*
X55658Y-668366D01*
Y-669206D01*
X55501Y-670046D01*
X55188Y-670781D01*
X54718Y-671411D01*
X54170Y-671831D01*
X53543Y-671936D01*
G01X59843Y-672146D02*
X59686Y-672041D01*
Y-671831D01*
X59843Y-671726D01*
X60000Y-671831D01*
Y-672041D01*
X59843Y-672146D01*
G01X67866Y-666161D02*
X67396Y-665846D01*
X66848Y-665636D01*
X66221D01*
X65516Y-665951D01*
X64968Y-666476D01*
X64576Y-667106D01*
X64263Y-668156D01*
X64185Y-669101D01*
X64341Y-670046D01*
X64576Y-670676D01*
X65046Y-671306D01*
X65595Y-671726D01*
X66143Y-671936D01*
X66691D01*
X67240Y-671726D01*
X67710Y-671411D01*
X68101Y-670991D01*
G01X72443Y-672146D02*
X72286Y-672041D01*
Y-671831D01*
X72443Y-671726D01*
X72600Y-671831D01*
Y-672041D01*
X72443Y-672146D01*
G01X-42680Y-661936D02*
Y-655636D01*
G01X-39704D02*
X-42680Y-659521D01*
G01X-39234Y-661936D02*
X-41349Y-657736D01*
G01X-36380Y-655636D02*
Y-660151D01*
X-36067Y-661096D01*
X-35440Y-661726D01*
X-34657Y-661936D01*
X-33874Y-661726D01*
X-33247Y-661096D01*
X-32934Y-660151D01*
Y-655636D01*
G01X-26790Y-661936D02*
X-29924D01*
Y-655636D01*
X-26790D01*
G01X-28044Y-658681D02*
X-29924D01*
G01X-22997Y-655636D02*
X-21117D01*
G01X-22057D02*
Y-661936D01*
G01X-22997D02*
X-21117D01*
G01X-11102Y-661096D02*
X-10475Y-661621D01*
X-9770Y-661936D01*
X-9144D01*
X-8517Y-661621D01*
X-8047Y-661096D01*
X-7812Y-660361D01*
X-7969Y-659626D01*
X-8360Y-658996D01*
X-9065Y-658576D01*
X-10005Y-658366D01*
X-10554Y-657946D01*
X-10789Y-657211D01*
X-10632Y-656476D01*
X-10240Y-655951D01*
X-9692Y-655636D01*
X-9144D01*
X-8595Y-655846D01*
X-8125Y-656371D01*
G01X-4802Y-661936D02*
Y-655636D01*
G01X-1512D02*
Y-661936D01*
G01Y-658786D02*
X-4802D01*
G01X1185Y-661936D02*
X3143Y-655636D01*
X5101Y-661936D01*
G01X4396Y-659731D02*
X1890D01*
G01X7641Y-661936D02*
Y-655636D01*
X11245Y-661936D01*
Y-655636D01*
G01X20398Y-661936D02*
Y-655636D01*
G01X23688D02*
Y-661936D01*
G01Y-658786D02*
X20398D01*
G01X26698Y-661096D02*
X27325Y-661621D01*
X28030Y-661936D01*
X28656D01*
X29283Y-661621D01*
X29753Y-661096D01*
X29988Y-660361D01*
X29831Y-659626D01*
X29440Y-658996D01*
X28735Y-658576D01*
X27795Y-658366D01*
X27246Y-657946D01*
X27011Y-657211D01*
X27168Y-656476D01*
X27560Y-655951D01*
X28108Y-655636D01*
X28656D01*
X29205Y-655846D01*
X29675Y-656371D01*
G01X33703Y-655636D02*
X35583D01*
G01X34643D02*
Y-661936D01*
G01X33703D02*
X35583D01*
G01X38985D02*
X40943Y-655636D01*
X42901Y-661936D01*
G01X42196Y-659731D02*
X39690D01*
G01X45441Y-661936D02*
Y-655636D01*
X49045Y-661936D01*
Y-655636D01*
G01X54013Y-658786D02*
X55580D01*
Y-660676D01*
X55110Y-661306D01*
X54561Y-661726D01*
X53778Y-661936D01*
X52995Y-661726D01*
X52446Y-661306D01*
X51976Y-660676D01*
X51663Y-659941D01*
X51506Y-659101D01*
Y-658366D01*
X51663Y-657736D01*
X51976Y-657001D01*
X52446Y-656371D01*
X52916Y-655951D01*
X53543Y-655636D01*
X54091D01*
X54718Y-655846D01*
X55188Y-656266D01*
G01X59686Y-663091D02*
X60000Y-661726D01*
G01X66143Y-655636D02*
Y-661936D01*
G01X64341Y-655636D02*
X67945D01*
G01X70485Y-661936D02*
X72443Y-655636D01*
X74401Y-661936D01*
G01X73696Y-659731D02*
X71190D01*
G01X78743Y-661936D02*
X78116Y-661831D01*
X77568Y-661411D01*
X77098Y-660781D01*
X76785Y-660046D01*
X76628Y-659206D01*
Y-658366D01*
X76785Y-657526D01*
X77098Y-656791D01*
X77568Y-656161D01*
X78116Y-655741D01*
X78743Y-655636D01*
X79370Y-655741D01*
X79918Y-656161D01*
X80388Y-656791D01*
X80701Y-657526D01*
X80858Y-658366D01*
Y-659206D01*
X80701Y-660046D01*
X80388Y-660781D01*
X79918Y-661411D01*
X79370Y-661831D01*
X78743Y-661936D01*
G01X91343D02*
Y-659101D01*
X89776Y-655636D01*
G01X92910D02*
X91343Y-659101D01*
G01X95920Y-655636D02*
Y-660151D01*
X96233Y-661096D01*
X96860Y-661726D01*
X97643Y-661936D01*
X98426Y-661726D01*
X99053Y-661096D01*
X99366Y-660151D01*
Y-655636D01*
G01X101985Y-661936D02*
X103943Y-655636D01*
X105901Y-661936D01*
G01X105196Y-659731D02*
X102690D01*
G01X108441Y-661936D02*
Y-655636D01*
X112045Y-661936D01*
Y-655636D01*
G01X-42759Y-651936D02*
Y-645636D01*
X-39155Y-651936D01*
Y-645636D01*
G01X-34657Y-651936D02*
X-35284Y-651831D01*
X-35832Y-651411D01*
X-36302Y-650781D01*
X-36615Y-650046D01*
X-36772Y-649206D01*
Y-648366D01*
X-36615Y-647526D01*
X-36302Y-646791D01*
X-35832Y-646161D01*
X-35284Y-645741D01*
X-34657Y-645636D01*
X-34030Y-645741D01*
X-33482Y-646161D01*
X-33012Y-646791D01*
X-32699Y-647526D01*
X-32542Y-648366D01*
Y-649206D01*
X-32699Y-650046D01*
X-33012Y-650781D01*
X-33482Y-651411D01*
X-34030Y-651831D01*
X-34657Y-651936D01*
G01X-28357Y-652146D02*
X-28514Y-652041D01*
Y-651831D01*
X-28357Y-651726D01*
X-28200Y-651831D01*
Y-652041D01*
X-28357Y-652146D01*
G01X-22057Y-651936D02*
Y-645636D01*
X-22997Y-646896D01*
G01Y-651936D02*
X-21117D01*
G01X-15757D02*
X-15209Y-651831D01*
X-14582Y-651516D01*
X-14190Y-650991D01*
X-14034Y-650256D01*
X-14190Y-649521D01*
X-14660Y-648891D01*
X-15365Y-648576D01*
X-16149D01*
X-16619Y-648366D01*
X-17010Y-647841D01*
X-17167Y-647106D01*
X-16932Y-646371D01*
X-16384Y-645846D01*
X-15757Y-645636D01*
X-15130Y-645846D01*
X-14582Y-646371D01*
X-14347Y-647106D01*
X-14504Y-647841D01*
X-14895Y-648366D01*
X-15365Y-648576D01*
X-16149D01*
X-16854Y-648891D01*
X-17324Y-649521D01*
X-17480Y-650256D01*
X-17324Y-650991D01*
X-16932Y-651516D01*
X-16305Y-651831D01*
X-15757Y-651936D01*
G01X-9457D02*
X-8909Y-651831D01*
X-8282Y-651516D01*
X-7890Y-650991D01*
X-7734Y-650256D01*
X-7890Y-649521D01*
X-8360Y-648891D01*
X-9065Y-648576D01*
X-9849D01*
X-10319Y-648366D01*
X-10710Y-647841D01*
X-10867Y-647106D01*
X-10632Y-646371D01*
X-10084Y-645846D01*
X-9457Y-645636D01*
X-8830Y-645846D01*
X-8282Y-646371D01*
X-8047Y-647106D01*
X-8204Y-647841D01*
X-8595Y-648366D01*
X-9065Y-648576D01*
X-9849D01*
X-10554Y-648891D01*
X-11024Y-649521D01*
X-11180Y-650256D01*
X-11024Y-650991D01*
X-10632Y-651516D01*
X-10005Y-651831D01*
X-9457Y-651936D01*
G01X-3314Y-653091D02*
X-3000Y-651726D01*
G01X793Y-645636D02*
X1890Y-651936D01*
X3143Y-645636D01*
X4396Y-651936D01*
X5493Y-645636D01*
G01X11010Y-651936D02*
X7876D01*
Y-645636D01*
X11010D01*
G01X9756Y-648681D02*
X7876D01*
G01X13941Y-651936D02*
Y-645636D01*
X17545Y-651936D01*
Y-645636D01*
G01X26698Y-651936D02*
Y-645636D01*
G01X29988D02*
Y-651936D01*
G01Y-648786D02*
X26698D01*
G01X32293Y-645636D02*
X33390Y-651936D01*
X34643Y-645636D01*
X35896Y-651936D01*
X36993Y-645636D01*
G01X38985Y-651936D02*
X40943Y-645636D01*
X42901Y-651936D01*
G01X42196Y-649731D02*
X39690D01*
G01X52055Y-646686D02*
X52525Y-646056D01*
X53073Y-645741D01*
X53700Y-645636D01*
X54483Y-645846D01*
X55031Y-646371D01*
X55188Y-647001D01*
X55110Y-647631D01*
X54796Y-648156D01*
X53230Y-649206D01*
X52525Y-649941D01*
X52055Y-650991D01*
X51898Y-651936D01*
X55188D01*
G01X58041D02*
Y-645636D01*
X61645Y-651936D01*
Y-645636D01*
G01X64420Y-651936D02*
Y-645636D01*
X65986D01*
X66613Y-645951D01*
X67083Y-646371D01*
X67475Y-647001D01*
X67788Y-647736D01*
X67866Y-648786D01*
X67788Y-649836D01*
X67475Y-650571D01*
X67083Y-651201D01*
X66613Y-651621D01*
X65986Y-651936D01*
X64420D01*
G01X77176D02*
Y-645636D01*
X79135D01*
X79761Y-645951D01*
X80153Y-646371D01*
X80310Y-647211D01*
X80153Y-648051D01*
X79683Y-648576D01*
X79135Y-648891D01*
X77176D01*
G01X79135D02*
X80310Y-651936D01*
G01X83320D02*
Y-645636D01*
X84886D01*
X85513Y-645951D01*
X85983Y-646371D01*
X86375Y-647001D01*
X86688Y-647736D01*
X86766Y-648786D01*
X86688Y-649836D01*
X86375Y-650571D01*
X85983Y-651201D01*
X85513Y-651621D01*
X84886Y-651936D01*
X83320D01*
G01X91343Y-652146D02*
X91186Y-652041D01*
Y-651831D01*
X91343Y-651726D01*
X91500Y-651831D01*
Y-652041D01*
X91343Y-652146D01*
G01X-18657Y-639236D02*
X-21177Y-638819D01*
X-23382Y-637153D01*
X-25272Y-634653D01*
X-26532Y-631736D01*
X-27162Y-628403D01*
Y-625069D01*
X-26532Y-621736D01*
X-25272Y-618819D01*
X-23382Y-616320D01*
X-21177Y-614653D01*
X-18657Y-614236D01*
X-16137Y-614653D01*
X-13932Y-616320D01*
X-12042Y-618819D01*
X-10782Y-621736D01*
X-10152Y-625069D01*
Y-628403D01*
X-10782Y-631736D01*
X-12042Y-634653D01*
X-13932Y-637153D01*
X-16137Y-638819D01*
X-18657Y-639236D01*
G01X-16137Y-632569D02*
X-12357Y-639236D01*
G01X1188Y-622570D02*
Y-634236D01*
X2448Y-637153D01*
X4338Y-638819D01*
X6543Y-639236D01*
X8748Y-638819D01*
X10638Y-637153D01*
X11898Y-634236D01*
G01Y-639236D02*
Y-622570D01*
G01X37413Y-639236D02*
Y-622570D01*
G01Y-625486D02*
X36153Y-623820D01*
X34263Y-622986D01*
X32058Y-622570D01*
X29853Y-623403D01*
X27963Y-625069D01*
X26703Y-627570D01*
X26073Y-630903D01*
X26703Y-634236D01*
X27963Y-636737D01*
X29853Y-638403D01*
X32058Y-639236D01*
X34263Y-638819D01*
X36153Y-637570D01*
X37413Y-635903D01*
G01X51588Y-639236D02*
Y-622570D01*
G01Y-626736D02*
X52848Y-624653D01*
X54738Y-622986D01*
X57258Y-622570D01*
X59463Y-622986D01*
X61353Y-624653D01*
X62298Y-627570D01*
Y-639236D01*
G01X82143Y-614236D02*
Y-639236D01*
G01X77733Y-622570D02*
X86553D01*
G01X113013Y-639236D02*
Y-622570D01*
G01Y-625486D02*
X111753Y-623820D01*
X109863Y-622986D01*
X107658Y-622570D01*
X105453Y-623403D01*
X103563Y-625069D01*
X102303Y-627570D01*
X101673Y-630903D01*
X102303Y-634236D01*
X103563Y-636737D01*
X105453Y-638403D01*
X107658Y-639236D01*
X109863Y-638819D01*
X111753Y-637570D01*
X113013Y-635903D01*
G01X152693Y-618936D02*
Y-626936D01*
X156693D01*
G01X164493D02*
Y-621603D01*
G01Y-622536D02*
X164093Y-622003D01*
X163493Y-621736D01*
X162793Y-621603D01*
X162093Y-621869D01*
X161493Y-622403D01*
X161093Y-623203D01*
X160893Y-624269D01*
X161093Y-625336D01*
X161493Y-626136D01*
X162093Y-626669D01*
X162793Y-626936D01*
X163493Y-626803D01*
X164093Y-626403D01*
X164493Y-625870D01*
G01X168593Y-629336D02*
X169193Y-629603D01*
X169993Y-629336D01*
X170493Y-628803D01*
X170893Y-628136D01*
X171493Y-626003D01*
X172793Y-621603D01*
G01X169593D02*
X171493Y-626003D01*
G01X177193Y-623336D02*
X180393D01*
X180093Y-622403D01*
X179593Y-621869D01*
X178893Y-621603D01*
X178193Y-621736D01*
X177593Y-622136D01*
X177193Y-623069D01*
X176993Y-623870D01*
Y-624669D01*
X177193Y-625469D01*
X177693Y-626269D01*
X178293Y-626803D01*
X178993Y-626936D01*
X179693Y-626669D01*
X180393Y-625870D01*
G01X185293Y-626936D02*
Y-621603D01*
G01Y-622669D02*
X185793Y-622136D01*
X186293Y-621736D01*
X186993Y-621603D01*
X187493Y-621736D01*
X188093Y-622136D01*
G01X173993Y-676936D02*
Y-668936D01*
G01X177793D02*
X173993Y-673870D01*
G01X178393Y-676936D02*
X175693Y-671603D01*
G01X185993Y-676936D02*
Y-671603D01*
G01Y-672536D02*
X185593Y-672003D01*
X184993Y-671736D01*
X184293Y-671603D01*
X183593Y-671869D01*
X182993Y-672403D01*
X182593Y-673203D01*
X182393Y-674269D01*
X182593Y-675336D01*
X182993Y-676136D01*
X183593Y-676669D01*
X184293Y-676936D01*
X184993Y-676803D01*
X185593Y-676403D01*
X185993Y-675870D01*
G01X192193Y-671603D02*
Y-676936D01*
G01Y-669469D02*
X191993Y-669336D01*
Y-669069D01*
X192193Y-668936D01*
X192393Y-669069D01*
Y-669336D01*
X192193Y-669469D01*
G01X184993Y-643936D02*
X187393D01*
G01X186193D02*
Y-651936D01*
G01X184993D02*
X187393D01*
G01X191893D02*
Y-643936D01*
X196493Y-651936D01*
Y-643936D01*
G01X199993Y-650336D02*
X200593Y-651269D01*
X201393Y-651803D01*
X202293Y-651936D01*
X203093Y-651803D01*
X203893Y-651136D01*
X204393Y-650336D01*
X204493Y-649536D01*
X204293Y-648603D01*
X203593Y-647936D01*
X202893Y-647669D01*
X201993D01*
G01X202893D02*
X203493Y-647269D01*
X203993Y-646603D01*
X204193Y-645803D01*
X203993Y-645003D01*
X203493Y-644336D01*
X202593Y-643936D01*
X201693Y-644069D01*
X200793Y-644603D01*
G01X206193Y-626936D02*
X206893Y-626803D01*
X207693Y-626403D01*
X208193Y-625736D01*
X208393Y-624803D01*
X208193Y-623870D01*
X207593Y-623069D01*
X206693Y-622669D01*
X205693D01*
X205093Y-622403D01*
X204593Y-621736D01*
X204393Y-620803D01*
X204693Y-619869D01*
X205393Y-619203D01*
X206193Y-618936D01*
X206993Y-619203D01*
X207693Y-619869D01*
X207993Y-620803D01*
X207793Y-621736D01*
X207293Y-622403D01*
X206693Y-622669D01*
X205693D01*
X204793Y-623069D01*
X204193Y-623870D01*
X203993Y-624803D01*
X204193Y-625736D01*
X204693Y-626403D01*
X205493Y-626803D01*
X206193Y-626936D01*
G01X279293Y-670269D02*
X279893Y-669469D01*
X280593Y-669069D01*
X281393Y-668936D01*
X282393Y-669203D01*
X283093Y-669869D01*
X283293Y-670669D01*
X283193Y-671470D01*
X282793Y-672136D01*
X280793Y-673469D01*
X279893Y-674403D01*
X279293Y-675736D01*
X279093Y-676936D01*
X283293D01*
G01X289193Y-668936D02*
X288393Y-669203D01*
X287793Y-669869D01*
X287393Y-670669D01*
X287093Y-671736D01*
X286993Y-672936D01*
X287093Y-674136D01*
X287393Y-675203D01*
X287793Y-676003D01*
X288393Y-676669D01*
X289193Y-676936D01*
X289993Y-676669D01*
X290593Y-676003D01*
X290993Y-675203D01*
X291293Y-674136D01*
X291393Y-672936D01*
X291293Y-671736D01*
X290993Y-670669D01*
X290593Y-669869D01*
X289993Y-669203D01*
X289193Y-668936D01*
G01X295293Y-670269D02*
X295893Y-669469D01*
X296593Y-669069D01*
X297393Y-668936D01*
X298393Y-669203D01*
X299093Y-669869D01*
X299293Y-670669D01*
X299193Y-671470D01*
X298793Y-672136D01*
X296793Y-673469D01*
X295893Y-674403D01*
X295293Y-675736D01*
X295093Y-676936D01*
X299293D01*
G01X303293Y-670269D02*
X303893Y-669469D01*
X304593Y-669069D01*
X305393Y-668936D01*
X306393Y-669203D01*
X307093Y-669869D01*
X307293Y-670669D01*
X307193Y-671470D01*
X306793Y-672136D01*
X304793Y-673469D01*
X303893Y-674403D01*
X303293Y-675736D01*
X303093Y-676936D01*
X307293D01*
G01X311393Y-677203D02*
X314993Y-668936D01*
G01X321193Y-676936D02*
Y-668936D01*
X319993Y-670536D01*
G01Y-676936D02*
X322393D01*
G01X327293Y-670269D02*
X327893Y-669469D01*
X328593Y-669069D01*
X329393Y-668936D01*
X330393Y-669203D01*
X331093Y-669869D01*
X331293Y-670669D01*
X331193Y-671470D01*
X330793Y-672136D01*
X328793Y-673469D01*
X327893Y-674403D01*
X327293Y-675736D01*
X327093Y-676936D01*
X331293D01*
G01X335393Y-677203D02*
X338993Y-668936D01*
G01X345193D02*
X344393Y-669203D01*
X343793Y-669869D01*
X343393Y-670669D01*
X343093Y-671736D01*
X342993Y-672936D01*
X343093Y-674136D01*
X343393Y-675203D01*
X343793Y-676003D01*
X344393Y-676669D01*
X345193Y-676936D01*
X345993Y-676669D01*
X346593Y-676003D01*
X346993Y-675203D01*
X347293Y-674136D01*
X347393Y-672936D01*
X347293Y-671736D01*
X346993Y-670669D01*
X346593Y-669869D01*
X345993Y-669203D01*
X345193Y-668936D01*
G01X351493Y-676003D02*
X352193Y-676669D01*
X352993Y-676936D01*
X353793Y-676669D01*
X354493Y-675870D01*
X354993Y-674669D01*
X355193Y-673469D01*
Y-672003D01*
X354993Y-670803D01*
X354493Y-669736D01*
X353893Y-669203D01*
X353193Y-668936D01*
X352393Y-669203D01*
X351793Y-669736D01*
X351393Y-670536D01*
X351193Y-671603D01*
X351393Y-672536D01*
X351893Y-673469D01*
X352493Y-674003D01*
X353193Y-674136D01*
X353993Y-673870D01*
X354593Y-673203D01*
X355193Y-672003D01*
G01X278993Y-651936D02*
Y-643936D01*
X280993D01*
X281793Y-644336D01*
X282393Y-644869D01*
X282893Y-645669D01*
X283293Y-646603D01*
X283393Y-647936D01*
X283293Y-649269D01*
X282893Y-650203D01*
X282393Y-651003D01*
X281793Y-651536D01*
X280993Y-651936D01*
X278993D01*
G01X286693D02*
X289193Y-643936D01*
X291693Y-651936D01*
G01X290793Y-649136D02*
X287593D01*
G01X297193Y-643936D02*
X296393Y-644203D01*
X295793Y-644869D01*
X295393Y-645669D01*
X295093Y-646736D01*
X294993Y-647936D01*
X295093Y-649136D01*
X295393Y-650203D01*
X295793Y-651003D01*
X296393Y-651669D01*
X297193Y-651936D01*
X297993Y-651669D01*
X298593Y-651003D01*
X298993Y-650203D01*
X299293Y-649136D01*
X299393Y-647936D01*
X299293Y-646736D01*
X298993Y-645669D01*
X298593Y-644869D01*
X297993Y-644203D01*
X297193Y-643936D01*
G01X303293Y-651936D02*
Y-643936D01*
X307093D01*
G01X305693Y-647803D02*
X303293D01*
G01X313193Y-643936D02*
X312393Y-644203D01*
X311793Y-644869D01*
X311393Y-645669D01*
X311093Y-646736D01*
X310993Y-647936D01*
X311093Y-649136D01*
X311393Y-650203D01*
X311793Y-651003D01*
X312393Y-651669D01*
X313193Y-651936D01*
X313993Y-651669D01*
X314593Y-651003D01*
X314993Y-650203D01*
X315293Y-649136D01*
X315393Y-647936D01*
X315293Y-646736D01*
X314993Y-645669D01*
X314593Y-644869D01*
X313993Y-644203D01*
X313193Y-643936D01*
G01X321193D02*
Y-651936D01*
G01X318893Y-643936D02*
X323493D01*
G01X326593Y-651936D02*
Y-643936D01*
X329193Y-650603D01*
X331793Y-643936D01*
Y-651936D01*
G01X334993D02*
Y-643936D01*
X336993D01*
X337793Y-644336D01*
X338393Y-644869D01*
X338893Y-645669D01*
X339293Y-646603D01*
X339393Y-647936D01*
X339293Y-649269D01*
X338893Y-650203D01*
X338393Y-651003D01*
X337793Y-651536D01*
X336993Y-651936D01*
X334993D01*
G01X347393Y-644603D02*
X346793Y-644203D01*
X346093Y-643936D01*
X345293D01*
X344393Y-644336D01*
X343693Y-645003D01*
X343193Y-645803D01*
X342793Y-647136D01*
X342693Y-648336D01*
X342893Y-649536D01*
X343193Y-650336D01*
X343793Y-651136D01*
X344493Y-651669D01*
X345193Y-651936D01*
X345893D01*
X346593Y-651669D01*
X347193Y-651269D01*
X347693Y-650736D01*
G01X350993Y-651936D02*
Y-643936D01*
X352993D01*
X353793Y-644336D01*
X354393Y-644869D01*
X354893Y-645669D01*
X355293Y-646603D01*
X355393Y-647936D01*
X355293Y-649269D01*
X354893Y-650203D01*
X354393Y-651003D01*
X353793Y-651536D01*
X352993Y-651936D01*
X350993D01*
G01X361193Y-643936D02*
X360393Y-644203D01*
X359793Y-644869D01*
X359393Y-645669D01*
X359093Y-646736D01*
X358993Y-647936D01*
X359093Y-649136D01*
X359393Y-650203D01*
X359793Y-651003D01*
X360393Y-651669D01*
X361193Y-651936D01*
X361993Y-651669D01*
X362593Y-651003D01*
X362993Y-650203D01*
X363293Y-649136D01*
X363393Y-647936D01*
X363293Y-646736D01*
X362993Y-645669D01*
X362593Y-644869D01*
X361993Y-644203D01*
X361193Y-643936D01*
G01X298418Y-624819D02*
Y-618519D01*
X301394D01*
G01X300298Y-621564D02*
X298418D01*
G01X306206Y-618519D02*
X305579Y-618729D01*
X305109Y-619254D01*
X304796Y-619884D01*
X304561Y-620724D01*
X304483Y-621669D01*
X304561Y-622614D01*
X304796Y-623454D01*
X305109Y-624084D01*
X305579Y-624609D01*
X306206Y-624819D01*
X306833Y-624609D01*
X307303Y-624084D01*
X307616Y-623454D01*
X307851Y-622614D01*
X307929Y-621669D01*
X307851Y-620724D01*
X307616Y-619884D01*
X307303Y-619254D01*
X306833Y-618729D01*
X306206Y-618519D01*
G01X312506D02*
Y-624819D01*
G01X310704Y-618519D02*
X314308D01*
G01X316456Y-626919D02*
X321156D01*
G01X323069Y-624819D02*
Y-618519D01*
X325106Y-623769D01*
X327143Y-618519D01*
Y-624819D01*
G01X332816D02*
Y-620619D01*
G01Y-621354D02*
X332503Y-620934D01*
X332033Y-620724D01*
X331484Y-620619D01*
X330936Y-620829D01*
X330466Y-621249D01*
X330153Y-621879D01*
X329996Y-622719D01*
X330153Y-623559D01*
X330466Y-624189D01*
X330936Y-624609D01*
X331484Y-624819D01*
X332033Y-624714D01*
X332503Y-624399D01*
X332816Y-623979D01*
G01X336374Y-624819D02*
Y-620619D01*
G01Y-621669D02*
X336688Y-621144D01*
X337158Y-620724D01*
X337784Y-620619D01*
X338333Y-620724D01*
X338803Y-621144D01*
X339038Y-621879D01*
Y-624819D01*
G01X345416D02*
Y-620619D01*
G01Y-621354D02*
X345103Y-620934D01*
X344633Y-620724D01*
X344084Y-620619D01*
X343536Y-620829D01*
X343066Y-621249D01*
X342753Y-621879D01*
X342596Y-622719D01*
X342753Y-623559D01*
X343066Y-624189D01*
X343536Y-624609D01*
X344084Y-624819D01*
X344633Y-624714D01*
X345103Y-624399D01*
X345416Y-623979D01*
G01X349209Y-626394D02*
X349758Y-626814D01*
X350384Y-626919D01*
X350933Y-626814D01*
X351403Y-626289D01*
X351716Y-625554D01*
Y-620619D01*
G01Y-621459D02*
X351403Y-621039D01*
X350933Y-620724D01*
X350384Y-620619D01*
X349758Y-620829D01*
X349366Y-621249D01*
X349053Y-621984D01*
X348896Y-622719D01*
X348974Y-623349D01*
X349288Y-624084D01*
X349758Y-624609D01*
X350384Y-624819D01*
X350854Y-624714D01*
X351403Y-624294D01*
X351716Y-623874D01*
G01X355431Y-621984D02*
X357938D01*
X357703Y-621249D01*
X357311Y-620829D01*
X356763Y-620619D01*
X356214Y-620724D01*
X355744Y-621039D01*
X355431Y-621774D01*
X355274Y-622404D01*
Y-623034D01*
X355431Y-623664D01*
X355823Y-624294D01*
X356293Y-624714D01*
X356841Y-624819D01*
X357389Y-624609D01*
X357938Y-623979D01*
G01X360556Y-624819D02*
Y-620619D01*
G01Y-621774D02*
X360791Y-621249D01*
X361183Y-620829D01*
X361731Y-620619D01*
X362279Y-620829D01*
X362671Y-621249D01*
X362906Y-621774D01*
Y-624819D01*
G01Y-621774D02*
X363141Y-621249D01*
X363533Y-620829D01*
X364081Y-620619D01*
X364629Y-620829D01*
X365021Y-621249D01*
X365256Y-621879D01*
Y-624819D01*
G01X368031Y-621984D02*
X370538D01*
X370303Y-621249D01*
X369911Y-620829D01*
X369363Y-620619D01*
X368814Y-620724D01*
X368344Y-621039D01*
X368031Y-621774D01*
X367874Y-622404D01*
Y-623034D01*
X368031Y-623664D01*
X368423Y-624294D01*
X368893Y-624714D01*
X369441Y-624819D01*
X369989Y-624609D01*
X370538Y-623979D01*
G01X374174Y-624819D02*
Y-620619D01*
G01Y-621669D02*
X374488Y-621144D01*
X374958Y-620724D01*
X375584Y-620619D01*
X376133Y-620724D01*
X376603Y-621144D01*
X376838Y-621879D01*
Y-624819D01*
G01X381806Y-618519D02*
Y-624819D01*
G01X380709Y-620619D02*
X382903D01*
G01X385756Y-626919D02*
X390456D01*
G01X395033Y-621459D02*
X395346Y-621144D01*
X395581Y-620619D01*
X395738Y-619884D01*
X395581Y-619254D01*
X395268Y-618834D01*
X394719Y-618519D01*
X392604D01*
Y-624819D01*
X395189D01*
X395738Y-624399D01*
X396051Y-623769D01*
X396208Y-623034D01*
X396051Y-622299D01*
X395581Y-621669D01*
X395033Y-621459D01*
X392604D01*
G01X398983Y-624819D02*
Y-618519D01*
X400549D01*
X401176Y-618834D01*
X401646Y-619254D01*
X402038Y-619884D01*
X402351Y-620619D01*
X402429Y-621669D01*
X402351Y-622719D01*
X402038Y-623454D01*
X401646Y-624084D01*
X401176Y-624504D01*
X400549Y-624819D01*
X398983D01*
G01X367693Y-679936D02*
Y-671936D01*
X366493Y-673536D01*
G01Y-679936D02*
X368893D01*
G01X373793Y-676603D02*
X374493Y-675669D01*
X375093Y-675136D01*
X375893Y-674869D01*
X376593Y-675136D01*
X377093Y-675669D01*
X377493Y-676469D01*
X377593Y-677403D01*
X377493Y-678203D01*
X377093Y-679003D01*
X376493Y-679669D01*
X375793Y-679936D01*
X374993Y-679669D01*
X374293Y-678870D01*
X373893Y-677669D01*
X373793Y-676336D01*
X373993Y-674603D01*
X374293Y-673669D01*
X374793Y-672736D01*
X375493Y-672069D01*
X376193Y-671936D01*
X376893Y-672203D01*
X377393Y-672869D01*
G01X383693Y-680203D02*
X383493Y-680069D01*
Y-679803D01*
X383693Y-679669D01*
X383893Y-679803D01*
Y-680069D01*
X383693Y-680203D01*
G01X389793Y-676603D02*
X390493Y-675669D01*
X391093Y-675136D01*
X391893Y-674869D01*
X392593Y-675136D01*
X393093Y-675669D01*
X393493Y-676469D01*
X393593Y-677403D01*
X393493Y-678203D01*
X393093Y-679003D01*
X392493Y-679669D01*
X391793Y-679936D01*
X390993Y-679669D01*
X390293Y-678870D01*
X389893Y-677669D01*
X389793Y-676336D01*
X389993Y-674603D01*
X390293Y-673669D01*
X390793Y-672736D01*
X391493Y-672069D01*
X392193Y-671936D01*
X392893Y-672203D01*
X393393Y-672869D01*
G01X412693Y-679936D02*
Y-671936D01*
X411493Y-673536D01*
G01Y-679936D02*
X413893D01*
G01X420493D02*
X420693Y-678203D01*
X420993Y-676736D01*
X421393Y-675403D01*
X421893Y-673936D01*
X422693Y-671936D01*
X418693D01*
G01X428693Y-680203D02*
X428493Y-680069D01*
Y-679803D01*
X428693Y-679669D01*
X428893Y-679803D01*
Y-680069D01*
X428693Y-680203D01*
G01X434793Y-673269D02*
X435393Y-672469D01*
X436093Y-672069D01*
X436893Y-671936D01*
X437893Y-672203D01*
X438593Y-672869D01*
X438793Y-673669D01*
X438693Y-674470D01*
X438293Y-675136D01*
X436293Y-676469D01*
X435393Y-677403D01*
X434793Y-678736D01*
X434593Y-679936D01*
X438793D01*
G01X432493Y-654936D02*
Y-646936D01*
X434493D01*
X435293Y-647336D01*
X435893Y-647869D01*
X436393Y-648669D01*
X436793Y-649603D01*
X436893Y-650936D01*
X436793Y-652269D01*
X436393Y-653203D01*
X435893Y-654003D01*
X435293Y-654536D01*
X434493Y-654936D01*
X432493D01*
G54D15*
G01X-25100Y250316D02*
Y239932D01*
X-24600Y239432D01*
X-21110D01*
X-17900Y236222D01*
Y231682D01*
X-21110Y228472D01*
X-37590D01*
X-38680Y227382D01*
Y225842D01*
X-37590Y224752D01*
X-21110D01*
X-17900Y221542D01*
Y217002D01*
X-21110Y213792D01*
X-37590D01*
X-38680Y212702D01*
Y211162D01*
X-37590Y210072D01*
X-21110D01*
X-17900Y206862D01*
Y202322D01*
X-21110Y199112D01*
X-37590D01*
X-38680Y198022D01*
Y196482D01*
X-37590Y195392D01*
X-21110D01*
X-17900Y192182D01*
Y187642D01*
X-21110Y184432D01*
X-37590D01*
X-38680Y183342D01*
Y181802D01*
X-37590Y180712D01*
X-21110D01*
X-17900Y177502D01*
Y172962D01*
X-21110Y169752D01*
X-37590D01*
X-38680Y168662D01*
Y167122D01*
X-37590Y166032D01*
X-21110D01*
X-17900Y162822D01*
Y158282D01*
X-21110Y155072D01*
X-33993D01*
X-34869Y155948D01*
Y157888D01*
X-34065Y158692D01*
X-22610D01*
X-21520Y159782D01*
Y161322D01*
X-22610Y162412D01*
X-39090D01*
X-42300Y165622D01*
Y170162D01*
X-39090Y173372D01*
X-22610D01*
X-21520Y174462D01*
Y176002D01*
X-22610Y177092D01*
X-39090D01*
X-42300Y180302D01*
Y184842D01*
X-39090Y188052D01*
X-22610D01*
X-21520Y189142D01*
Y190682D01*
X-22610Y191772D01*
X-39090D01*
X-42300Y194982D01*
Y199522D01*
X-39090Y202732D01*
X-22610D01*
X-21520Y203822D01*
Y205362D01*
X-22610Y206452D01*
X-39090D01*
X-42300Y209662D01*
Y214202D01*
X-39090Y217412D01*
X-22610D01*
X-21520Y218502D01*
Y220042D01*
X-22610Y221132D01*
X-39090D01*
X-42300Y224342D01*
Y228882D01*
X-39090Y232092D01*
X-22610D01*
X-21520Y233182D01*
Y234722D01*
X-22610Y235812D01*
X-34600D01*
X-35100Y236312D01*
Y250316D01*
G01X14000Y401700D02*
X9580Y397280D01*
Y344991D01*
X16671Y337900D01*
X18074Y334512D01*
Y316810D01*
X7248Y305984D01*
Y37538D01*
X14846Y29940D01*
X55214D01*
X58474Y33200D01*
X197500D01*
X211400Y47100D01*
Y59238D01*
G01X14000Y406700D02*
X13940D01*
X8560Y401320D01*
Y344568D01*
X15806Y337322D01*
X17054Y334309D01*
Y317233D01*
X6228Y306407D01*
Y37115D01*
X14423Y28920D01*
X55820D01*
X59080Y32180D01*
X197923D01*
X214500Y48757D01*
Y57500D01*
X215700Y58700D01*
X227600D01*
X229900Y61000D01*
G01X54100Y448600D02*
Y447000D01*
X50300Y443200D01*
X38500D01*
X7300Y412000D01*
Y344384D01*
X14942Y336742D01*
X16034Y334106D01*
Y317656D01*
X5208Y306830D01*
Y36692D01*
X14000Y27900D01*
X51700D01*
X54200Y25400D01*
G01X204100Y67400D02*
X202830D01*
X184450Y49020D01*
X154147D01*
X148547Y54620D01*
X138653D01*
X131992Y47959D01*
Y45767D01*
X129224Y42999D01*
X125549D01*
X120732Y47816D01*
X110642D01*
X106120Y52338D01*
X103328D01*
X102700Y51710D01*
Y37300D01*
X99920Y34520D01*
X57829D01*
X57393Y34084D01*
X48416D01*
X39000Y43500D01*
Y72500D01*
X34800Y76700D01*
X18812D01*
X8568Y86944D01*
Y305435D01*
X19394Y316261D01*
Y334775D01*
X17790Y338648D01*
X11651Y344787D01*
Y354126D01*
X15810Y358285D01*
Y418610D01*
X28100Y430900D01*
X29400D01*
G01X52120Y78373D02*
X44127D01*
X40500Y82000D01*
Y94500D01*
X32330Y102670D01*
X29293D01*
X10908Y121055D01*
Y305908D01*
X22920Y317920D01*
Y319755D01*
X23614Y320449D01*
X25450Y321210D01*
X26010D01*
X30000Y325200D01*
Y328600D01*
X31300Y329900D01*
G01X13869Y352239D02*
Y347931D01*
X19400Y342400D01*
Y339190D01*
X20807Y335793D01*
X22700Y333900D01*
X24800D01*
X25700Y333000D01*
Y327600D01*
X23200Y325100D01*
Y323144D01*
X23810Y322534D01*
G01X31500Y428500D02*
Y427314D01*
X17220Y413034D01*
Y348213D01*
X21653Y343780D01*
X25754D01*
X27900Y341634D01*
Y333300D01*
X31300Y329900D01*
G01X33000Y318700D02*
X34618Y317082D01*
X38888D01*
X43880Y312090D01*
Y301966D01*
X46690Y299156D01*
X48244D01*
X49379Y298021D01*
Y265017D01*
X47279Y262917D01*
Y232561D01*
X50700Y229140D01*
Y219800D01*
X49869Y218969D01*
Y211821D01*
X47130Y209082D01*
Y201818D01*
X47948Y201000D01*
G01X73400Y313700D02*
X71997Y315103D01*
X71403D01*
X64992Y308692D01*
X53407D01*
X47599Y314500D01*
X43337D01*
X39435Y318402D01*
X36298D01*
X33810Y320890D01*
Y332691D01*
X33271Y333230D01*
Y344560D01*
X32730Y345101D01*
X25208D01*
X25207Y345100D01*
X22200D01*
X18540Y348760D01*
Y412386D01*
X34459Y428305D01*
Y433086D01*
X42865Y441492D01*
X64749D01*
X70157Y446900D01*
X73131D01*
X82531Y456300D01*
X112281D01*
X124481Y444100D01*
X135500D01*
X139900Y448500D01*
Y450350D01*
X138750Y451500D01*
G01X52800Y322400D02*
Y317060D01*
X51840Y316100D01*
X50300D01*
X45830Y320570D01*
X43102D01*
X40262Y323410D01*
X37170D01*
X36750Y323830D01*
Y330750D01*
X39150Y333150D01*
Y343249D01*
X31380Y351019D01*
Y356811D01*
X29880Y358311D01*
Y374828D01*
X28080Y376628D01*
Y412180D01*
X54452Y438552D01*
X65968D01*
X70916Y443500D01*
X90500D01*
X93340Y440660D01*
X112297D01*
X112977Y441340D01*
Y443929D01*
X112297Y444609D01*
X108928D01*
X108248Y445289D01*
Y446250D01*
X108928Y446930D01*
X112297D01*
X112977Y447610D01*
Y448074D01*
X113657Y448754D01*
X114618D01*
X115298Y448074D01*
Y441340D01*
X115978Y440660D01*
X137160D01*
X150300Y453800D01*
X154800D01*
X155210Y453390D01*
X157500D01*
G01X50950Y318050D02*
Y322149D01*
X49499Y323600D01*
X47301D01*
X45891Y322190D01*
X43775D01*
X40770Y325195D01*
Y346731D01*
X37442Y350059D01*
X34840D01*
X33000Y351899D01*
Y357483D01*
X31500Y358983D01*
Y375500D01*
X29700Y377300D01*
Y411508D01*
X55124Y436932D01*
X66640D01*
X71182Y441474D01*
X80826D01*
X81750Y440550D01*
X82712D01*
X83771Y441609D01*
X84733D01*
X85413Y440929D01*
Y439967D01*
X84354Y438908D01*
Y437946D01*
X86500Y435800D01*
X90512D01*
X91192Y435120D01*
Y434743D01*
X91872Y434063D01*
X92833D01*
X93513Y434743D01*
Y435120D01*
X94193Y435800D01*
X98830D01*
X99510Y436480D01*
Y438235D01*
X100190Y438915D01*
X101151D01*
X101831Y438235D01*
Y436480D01*
X102511Y435800D01*
X104001D01*
X105615Y436468D01*
X106503Y436100D01*
X106748Y435508D01*
X107635Y435140D01*
X108525Y435509D01*
X108893Y436397D01*
X108648Y436989D01*
X109016Y437877D01*
X111823Y439040D01*
X137832D01*
X148722Y449930D01*
X151398D01*
G01X138750Y454500D02*
X141600Y451650D01*
Y448001D01*
X136179Y442580D01*
X123250D01*
X110930Y454900D01*
X83700D01*
X74080Y445280D01*
X70404D01*
X65296Y440172D01*
X43412D01*
X35780Y432540D01*
Y427759D01*
X19860Y411839D01*
Y353780D01*
X20280Y353360D01*
X26339D01*
X37500Y342199D01*
Y334000D01*
X35130Y331630D01*
Y322870D01*
X38278Y319722D01*
X39982D01*
X40754Y318950D01*
X45158D01*
X50508Y313600D01*
X55280D01*
X58803Y310077D01*
X64510D01*
X71563Y317130D01*
X76470D01*
X77500Y316100D01*
G01X224000Y74275D02*
Y71621D01*
X219479Y67100D01*
X211100D01*
X208800Y69400D01*
X201099D01*
X194069Y62370D01*
X150970D01*
X144540Y55940D01*
X138106D01*
X133100Y50934D01*
X111766D01*
X107659Y55041D01*
X99471D01*
X97012Y57500D01*
X72100D01*
X66600Y63000D01*
Y68004D01*
X61866Y72738D01*
Y76440D01*
X55380Y82926D01*
Y110519D01*
X54160Y111739D01*
Y131343D01*
X56261Y136423D01*
X56263Y137683D01*
X57200Y139945D01*
Y178363D01*
X50600Y184963D01*
Y192735D01*
X45200Y198135D01*
Y209020D01*
X45900Y209720D01*
Y218297D01*
X49380Y221777D01*
Y228593D01*
X45959Y232014D01*
Y263759D01*
X46220Y264020D01*
Y277170D01*
G01X71200Y431700D02*
X69500D01*
X56300Y418500D01*
X53352D01*
X50520Y415668D01*
Y411188D01*
X47932Y408600D01*
X43452D01*
X40500Y405648D01*
Y350500D01*
X42410Y348590D01*
Y337930D01*
X42390Y337910D01*
Y326135D01*
X44525Y324000D01*
G01X63000Y324100D02*
X61300Y322400D01*
X55030D01*
X54610Y322820D01*
Y324800D01*
X55060Y325888D01*
Y326470D01*
X54450Y327080D01*
X51545D01*
X51345Y327280D01*
X51344D01*
X46460Y332164D01*
Y384765D01*
X49500Y392109D01*
Y402500D01*
X55190Y408190D01*
Y410202D01*
X62518Y417530D01*
X75430D01*
X77592Y419692D01*
X84282D01*
X95190Y430600D01*
X116500D01*
X119500Y433600D01*
G01X56600Y324300D02*
X58117D01*
X58800Y324983D01*
Y326300D01*
X56391Y328709D01*
X52208D01*
X52017Y328900D01*
X52016D01*
X48080Y332836D01*
Y384441D01*
X51120Y391782D01*
Y401721D01*
X56810Y407411D01*
Y409530D01*
X63190Y415910D01*
X76102D01*
X78264Y418072D01*
X95572D01*
X101100Y423600D01*
Y427200D01*
X102880Y428980D01*
X119140D01*
X121360Y431200D01*
X137100D01*
X147200Y441300D01*
X153800D01*
X158500Y446000D01*
Y446800D01*
X158970Y447270D01*
X162541Y448750D01*
X163313Y448430D01*
X165063Y444209D01*
X165835Y443889D01*
X166610Y444211D01*
X166930Y444983D01*
X165180Y449204D01*
X165500Y449976D01*
X167165Y450665D01*
X171335D01*
X171400Y450600D01*
G01X88565Y426535D02*
X82965D01*
X80300Y429200D01*
X69292D01*
X57924Y417832D01*
Y415228D01*
X53570Y410874D01*
Y408862D01*
X48642Y403934D01*
X43324D01*
X42120Y402730D01*
Y353400D01*
X43920Y351600D01*
X44500D01*
G01X59511Y424477D02*
X55234Y420200D01*
X52760D01*
X48900Y416340D01*
Y412410D01*
X46890Y410400D01*
X42990D01*
X42290Y411100D01*
X36110D01*
X34790Y409780D01*
Y407850D01*
X35101Y407539D01*
Y381610D01*
G01X42900Y412900D02*
Y415500D01*
X48700Y421300D01*
Y428216D01*
X55796Y435312D01*
X67312D01*
X71854Y439854D01*
X80154D01*
X87700Y432308D01*
X115608D01*
X120720Y437420D01*
X138504D01*
X146184Y445100D01*
X152600D01*
X155100Y447600D01*
Y449204D01*
X157476Y451580D01*
X159144D01*
X162519Y452978D01*
X168029Y456660D01*
G01X125800Y47330D02*
X123755Y49375D01*
X111236D01*
X106939Y53672D01*
X102470D01*
X100390Y51592D01*
Y49998D01*
X98415Y48023D01*
X92904D01*
X91137Y49790D01*
Y54608D01*
X89647Y56098D01*
X60707D01*
X55613Y61192D01*
Y67569D01*
X51881Y71301D01*
Y75459D01*
X54772Y78350D01*
Y81503D01*
X53400Y82875D01*
Y102788D01*
G01X275386Y102710D02*
Y100914D01*
X280400Y95900D01*
Y93300D01*
X274520Y87420D01*
X268853D01*
X262153Y80720D01*
X247892D01*
X239772Y72600D01*
X233700D01*
X230129Y76171D01*
X223091D01*
X222190Y75270D01*
Y74030D01*
X219360Y71200D01*
X200800D01*
X193290Y63690D01*
X150423D01*
X143993Y57260D01*
X137559D01*
X133466Y53167D01*
X115083D01*
X113100Y55150D01*
X109794D01*
X108517Y56427D01*
X100009D01*
X97356Y59080D01*
X74700D01*
X70500Y63280D01*
Y67660D01*
X63634Y74526D01*
Y76750D01*
X56700Y83684D01*
Y111066D01*
X55480Y112286D01*
Y131080D01*
X57581Y136157D01*
X57583Y137419D01*
X58520Y139681D01*
Y178910D01*
X52410Y185020D01*
Y186900D01*
G01X256900Y87300D02*
X250737D01*
X240117Y76680D01*
X237457D01*
X235282Y78855D01*
X219702D01*
X214687Y73840D01*
X192337D01*
X189907Y71410D01*
X186479D01*
X181399Y66330D01*
X148995D01*
X144375Y61710D01*
X118809D01*
X115199Y58100D01*
X110683D01*
X109652Y59131D01*
X101133D01*
X98264Y62000D01*
X81403D01*
X78500Y64903D01*
Y68246D01*
X78000Y68746D01*
X76606D01*
X71615Y73737D01*
Y75293D01*
X59340Y87568D01*
Y112160D01*
X58120Y113380D01*
Y130554D01*
X59660Y134270D01*
X60573Y134880D01*
X62243D01*
X63163Y135800D01*
Y137296D01*
X61160Y142133D01*
Y180004D01*
X56206Y184958D01*
Y200633D01*
X58603Y203030D01*
X59776D01*
X61210Y204464D01*
Y208895D01*
X61953Y209638D01*
Y223778D01*
X60520Y225211D01*
Y232560D01*
X57880Y235200D01*
Y238951D01*
X64399Y254689D01*
X65755Y256045D01*
G01X251900Y100100D02*
Y99381D01*
X239219Y86700D01*
X222499D01*
X212279Y76480D01*
X191243D01*
X188813Y74050D01*
X185385D01*
X180305Y68970D01*
X147701D01*
X143081Y64350D01*
X112867D01*
X109817Y67400D01*
X107800D01*
X102000Y73200D01*
Y76000D01*
X97885Y80115D01*
X70840D01*
X61980Y88975D01*
Y111433D01*
X63242Y112695D01*
Y115226D01*
X63160Y115308D01*
Y127970D01*
X63863Y131503D01*
X64703Y133531D01*
X65439Y134022D01*
X66065Y134648D01*
Y138456D01*
X65171Y139350D01*
X63800Y142660D01*
Y181098D01*
X59531Y185367D01*
Y192242D01*
X62240Y194951D01*
Y201760D01*
X63850Y203370D01*
Y207801D01*
X64593Y208544D01*
Y224872D01*
X63160Y226305D01*
Y232695D01*
X65760Y235295D01*
Y245833D01*
X72120Y252193D01*
Y261762D01*
X70287Y263595D01*
X68072D01*
X65630Y266037D01*
Y272330D01*
X71900Y278600D01*
Y285900D01*
X75900Y289900D01*
Y290500D01*
X75870Y290530D01*
Y290700D01*
G01X68990Y260465D02*
X68264D01*
X67415Y259616D01*
X64042Y257362D01*
X56560Y239298D01*
Y234653D01*
X59200Y232013D01*
Y224664D01*
X60633Y223231D01*
Y210185D01*
X59890Y209442D01*
Y205011D01*
X59229Y204350D01*
X58056D01*
X54886Y201180D01*
Y184411D01*
X59840Y179457D01*
Y139416D01*
X58903Y137155D01*
X58901Y135893D01*
X56800Y130817D01*
Y112833D01*
X58020Y111613D01*
Y86998D01*
X69488Y75530D01*
Y72686D01*
X74310Y67864D01*
Y62390D01*
X76300Y60400D01*
X97908D01*
X100512Y57796D01*
X109090D01*
X110386Y56500D01*
X114300D01*
X116233Y54567D01*
X132967D01*
X137200Y58800D01*
X143332D01*
X149542Y65010D01*
X181832D01*
X193804Y67391D01*
X196001Y68301D01*
X200220Y72520D01*
X215234D01*
X220247Y77533D01*
X234737D01*
X236910Y75360D01*
X240664D01*
X250104Y84800D01*
X259702D01*
X264245Y86682D01*
X273400Y92800D01*
G01X251200Y93800D02*
X249510D01*
X240996Y85286D01*
X223034D01*
X212908Y75160D01*
X191790D01*
X189360Y72730D01*
X185932D01*
X180852Y67650D01*
X148448D01*
X143828Y63030D01*
X110530D01*
X108000Y60500D01*
X101708D01*
X101705Y60501D01*
X98706Y63500D01*
X84000D01*
X82500Y65000D01*
Y69200D01*
X81449Y70251D01*
X77181D01*
X72966Y74466D01*
Y75810D01*
X60660Y88116D01*
Y111980D01*
X61922Y113242D01*
Y114678D01*
X61840Y114760D01*
Y128103D01*
X62592Y131885D01*
X63637Y134407D01*
X64598Y135048D01*
X64745Y135195D01*
Y137909D01*
X64052Y138602D01*
X62480Y142397D01*
Y180551D01*
X57526Y185505D01*
Y200086D01*
X59150Y201710D01*
X60323D01*
X62530Y203917D01*
Y208348D01*
X63273Y209091D01*
Y224325D01*
X61840Y225758D01*
Y236460D01*
X61300Y237000D01*
Y238796D01*
X64443Y246383D01*
X70800Y252740D01*
Y261215D01*
X69740Y262275D01*
X67525D01*
X64310Y265490D01*
Y273250D01*
X56740Y280820D01*
Y291560D01*
X58710Y293530D01*
X68630D01*
X70500Y295400D01*
Y304600D01*
X71500Y305600D01*
Y309200D01*
X76500Y314200D01*
X78200D01*
X79800Y315800D01*
Y320700D01*
X81000Y321900D01*
G01X68960Y173300D02*
X66440Y175820D01*
Y182193D01*
X62171Y186462D01*
Y191148D01*
X64960Y193937D01*
Y197404D01*
X67490Y199934D01*
Y202620D01*
X66490Y203620D01*
Y206646D01*
X67233Y207389D01*
Y225967D01*
X65800Y227400D01*
Y231600D01*
X68400Y234200D01*
Y244739D01*
X74760Y251099D01*
Y262856D01*
X71380Y266236D01*
X70288D01*
X70287Y266235D01*
X69166D01*
X68598Y266803D01*
Y271564D01*
X74284Y277250D01*
X75685D01*
X78600Y280165D01*
Y283970D01*
G01X212991Y162898D02*
X214529Y161360D01*
X226140D01*
X227130Y160370D01*
Y157157D01*
X229510Y154777D01*
Y151138D01*
X228933Y150561D01*
Y143602D01*
X238030Y134505D01*
Y122470D01*
X241189Y119311D01*
X243562D01*
X244622Y118251D01*
Y116751D01*
X243562Y115691D01*
X243561D01*
X242796Y114926D01*
Y113050D01*
X243830Y112016D01*
Y104931D01*
X242777Y103878D01*
Y102423D01*
X243790Y101410D01*
X246150D01*
X247643Y99917D01*
Y96991D01*
X238862Y88210D01*
X222142D01*
X211732Y77800D01*
X190696D01*
X188266Y75370D01*
X184838D01*
X179758Y70290D01*
X147153D01*
X142533Y65670D01*
X115963D01*
X99698Y81935D01*
X70888D01*
X63300Y89523D01*
Y110886D01*
X64562Y112148D01*
Y115774D01*
X64480Y115856D01*
Y127833D01*
X65134Y131122D01*
X65769Y132655D01*
X66280Y132996D01*
X67385Y134101D01*
Y139003D01*
X66290Y140098D01*
X65120Y142924D01*
Y181646D01*
X60851Y185915D01*
Y191695D01*
X63640Y194484D01*
Y197951D01*
X66020Y200331D01*
Y202223D01*
X65170Y203073D01*
Y207193D01*
X65913Y207936D01*
Y225419D01*
X64480Y226852D01*
Y232148D01*
X67080Y234748D01*
Y245286D01*
X73440Y251646D01*
Y262309D01*
X70834Y264915D01*
X68619D01*
X66950Y266584D01*
Y271783D01*
X73823Y278656D01*
Y285923D01*
X75000Y287100D01*
X78400D01*
X86985Y295685D01*
X88397D01*
X90600Y297888D01*
Y326900D01*
X88400Y329100D01*
X82140D01*
X79100Y326060D01*
Y322400D01*
X77890Y321190D01*
X71910D01*
X71000Y322100D01*
Y329633D01*
X67664Y332969D01*
X53974D01*
X52340Y334603D01*
Y347339D01*
X57054Y352053D01*
Y369119D01*
X58035Y370100D01*
G01X52410Y190190D02*
Y192920D01*
X50750Y194580D01*
Y203100D01*
X54580Y206930D01*
Y260710D01*
X52610Y262680D01*
Y299550D01*
X56270Y303210D01*
X64230D01*
G01X60613Y312012D02*
X58600Y314025D01*
Y319780D01*
X59600Y320780D01*
X62380D01*
X64900Y323300D01*
Y327332D01*
X61903Y330329D01*
X52880D01*
X49700Y333509D01*
Y371200D01*
X51390Y372890D01*
X55150D01*
X56400Y374140D01*
Y391027D01*
X54060Y393367D01*
Y399560D01*
X60120Y405620D01*
X66153D01*
X67000Y406467D01*
Y408800D01*
G01X60600Y318000D02*
X63500D01*
X66600Y321100D01*
Y327499D01*
X62450Y331649D01*
X53427D01*
X51020Y334056D01*
Y348020D01*
X55800Y352800D01*
Y364200D01*
X51800Y368200D01*
Y370800D01*
X52570Y371570D01*
X55697D01*
X57420Y373293D01*
Y391450D01*
X55380Y393490D01*
Y398980D01*
X60700Y404300D01*
X66700D01*
X69700Y407300D01*
Y408800D01*
G01X76900Y323000D02*
X75900D01*
X74600Y324300D01*
Y327900D01*
X68211Y334289D01*
X54521D01*
X53660Y335150D01*
Y345460D01*
X60200Y352000D01*
Y356892D01*
X60420Y357112D01*
Y372180D01*
X58740Y373860D01*
Y391997D01*
X56700Y394037D01*
Y398199D01*
X61481Y402980D01*
X67780D01*
X71570Y406770D01*
Y411021D01*
X69139Y413452D01*
G01X54400Y374700D02*
X55000Y375300D01*
Y390560D01*
X52740Y392820D01*
Y400241D01*
X61100Y408601D01*
Y409700D01*
X63100Y411700D01*
X64527D01*
X66319Y413492D01*
G01X140730Y72600D02*
X138100D01*
X137070Y71570D01*
X116370D01*
X114500Y73440D01*
Y75500D01*
X115500Y76500D01*
Y82000D01*
X111000Y86500D01*
Y93500D01*
X105400Y99100D01*
Y106166D01*
X107880Y108646D01*
Y112053D01*
X106070Y113863D01*
Y120796D01*
X103260Y123606D01*
Y127540D01*
X100600Y130200D01*
Y150873D01*
X76800Y174673D01*
Y179756D01*
X77110Y180066D01*
Y184603D01*
X74200Y191629D01*
Y197883D01*
X75230Y200370D01*
Y205772D01*
X72500Y208502D01*
Y214000D01*
G01X80300Y243700D02*
Y242760D01*
X78600Y241060D01*
Y231700D01*
X75180Y228280D01*
Y222007D01*
X69873Y216700D01*
Y209648D01*
X74000Y205521D01*
Y200400D01*
X71200Y197600D01*
X69200D01*
X67600Y196000D01*
Y194601D01*
X69296Y192905D01*
Y177572D01*
X75548Y171320D01*
X77814D01*
X93150Y155984D01*
Y149143D01*
X99400Y142893D01*
Y124400D01*
X104106Y119694D01*
Y95606D01*
X102320Y93820D01*
Y92000D01*
X105320Y89000D01*
X107000D01*
X114000Y82000D01*
Y77000D01*
X113000Y76000D01*
Y73000D01*
X117690Y68310D01*
X139910D01*
X145000Y73400D01*
X156690D01*
X156710Y73420D01*
G01X90923Y293520D02*
X90448Y293045D01*
X88246D01*
X80910Y285709D01*
Y280955D01*
X79710Y278058D01*
Y273950D01*
X78400Y272640D01*
Y264357D01*
X79247Y263510D01*
Y262302D01*
X79200Y262188D01*
X79194Y262182D01*
Y253019D01*
X78400Y252225D01*
Y244999D01*
X75647Y242246D01*
Y234817D01*
X68553Y227723D01*
Y209101D01*
X70200Y207454D01*
Y203000D01*
X69000Y201800D01*
Y199300D01*
X66280Y196580D01*
Y193390D01*
X63491Y190601D01*
Y187011D01*
X67760Y182742D01*
Y177241D01*
X75001Y170000D01*
X77229D01*
X91830Y155399D01*
Y139070D01*
X98080Y132820D01*
Y123853D01*
X102786Y119147D01*
Y96500D01*
X101000Y94714D01*
Y90632D01*
X104132Y87500D01*
X106500D01*
X109000Y85000D01*
Y74500D01*
X116510Y66990D01*
X141986D01*
X146606Y71610D01*
X179211D01*
X184291Y76690D01*
X187719D01*
X190149Y79120D01*
X210901D01*
X222389Y90600D01*
X226940D01*
X229850Y93510D01*
X233450D01*
X238840Y98900D01*
Y101810D01*
X237820Y102830D01*
X235152D01*
X233820Y104162D01*
Y106610D01*
X236400Y109190D01*
Y125040D01*
X236710Y125350D01*
Y133958D01*
X227613Y143055D01*
Y151813D01*
X227700Y151900D01*
G01X186300Y448700D02*
X178310Y440710D01*
X164910D01*
X159275Y435075D01*
Y421375D01*
X156400Y418500D01*
Y411500D01*
X146980Y402080D01*
Y395471D01*
X131600Y380091D01*
Y368533D01*
X127230Y364163D01*
Y360803D01*
X121170Y354743D01*
Y346142D01*
X114338Y339310D01*
X114001D01*
X112590Y337899D01*
Y328846D01*
X111470Y327726D01*
Y323483D01*
X106910Y318923D01*
Y308550D01*
X106125Y307765D01*
X105436Y307480D01*
X103514D01*
X95880Y299846D01*
Y295020D01*
X95881Y295019D01*
Y293927D01*
X92234Y290280D01*
X90079D01*
X85609Y285810D01*
X84745D01*
X83550Y284615D01*
Y280429D01*
X82350Y277528D01*
Y272856D01*
X81040Y271546D01*
Y265451D01*
X81887Y264604D01*
Y261777D01*
X81834Y261649D01*
Y256366D01*
X85420Y252780D01*
Y241553D01*
X82520Y238653D01*
Y233053D01*
X77160Y227693D01*
Y211822D01*
X74860Y209522D01*
Y208010D01*
X76550Y206320D01*
Y200052D01*
X75800Y198241D01*
Y191218D01*
X77900Y186148D01*
Y186146D01*
X78430Y184866D01*
Y179519D01*
X78120Y179209D01*
Y175234D01*
X103400Y149954D01*
Y138533D01*
X105060Y136873D01*
Y130654D01*
X104750Y130344D01*
Y123983D01*
X107390Y121343D01*
Y114410D01*
X109300Y112500D01*
Y107667D01*
X107880Y106247D01*
Y102853D01*
X110575Y100158D01*
Y97000D01*
X112500Y95075D01*
Y87500D01*
X118618Y81382D01*
Y78618D01*
X124346Y72890D01*
X131838D01*
X138298Y79350D01*
X143890D01*
X146740Y76500D01*
X149100D01*
X150300Y77700D01*
X154990D01*
X159100Y73590D01*
X179324D01*
X183744Y78010D01*
X187172D01*
X189602Y80440D01*
X203007D01*
X218267Y95700D01*
X226795D01*
X232325Y101230D01*
G01X185000Y451500D02*
X187900D01*
X188520Y450880D01*
Y448120D01*
X179390Y438990D01*
X165096D01*
X160595Y434489D01*
Y420495D01*
X157720Y417620D01*
Y410953D01*
X148300Y401533D01*
Y394924D01*
X132920Y379544D01*
Y367986D01*
X128550Y363616D01*
Y360256D01*
X122490Y354196D01*
Y345268D01*
X117500Y340278D01*
Y331889D01*
X112790Y327179D01*
Y322936D01*
X108230Y318376D01*
Y308003D01*
X106872Y306645D01*
X105701Y306160D01*
X104061D01*
X97500Y299599D01*
Y293679D01*
X87530Y283709D01*
Y282364D01*
X85730Y280564D01*
Y264609D01*
X86350Y263989D01*
Y256381D01*
X86740Y255991D01*
Y241006D01*
X83840Y238106D01*
Y232506D01*
X78480Y227146D01*
Y201093D01*
X77200Y198002D01*
Y191290D01*
X79300Y186219D01*
Y186217D01*
X79750Y185129D01*
Y178972D01*
X79440Y178662D01*
Y175805D01*
X104720Y150525D01*
Y145015D01*
X105429Y144306D01*
X108441D01*
X109150Y143597D01*
Y142595D01*
X108441Y141886D01*
X105429D01*
X104720Y141177D01*
Y139080D01*
X106380Y137420D01*
Y130107D01*
X106070Y129797D01*
Y124530D01*
X111900Y118700D01*
Y111100D01*
X111895Y111095D01*
Y108395D01*
X109200Y105700D01*
Y103400D01*
X111895Y100705D01*
Y98000D01*
X114500Y95395D01*
Y88000D01*
X120274Y82226D01*
Y78829D01*
X122442Y76661D01*
X125037D01*
X126376Y78000D01*
X132637D01*
X135307Y80670D01*
X143516D01*
X143916Y81070D01*
X153488D01*
X158158Y76400D01*
X163500D01*
X166550Y79450D01*
X186745D01*
X189055Y81760D01*
X195360D01*
X200100Y86500D01*
X207200D01*
X218100Y97400D01*
X222220D01*
X226040Y101220D01*
G01X75960Y284049D02*
X77691Y285780D01*
X79081D01*
X87666Y294365D01*
X88944D01*
X91920Y297341D01*
Y316220D01*
X95700Y320000D01*
X97600D01*
X99800Y322200D01*
Y325027D01*
X102330Y327557D01*
Y328876D01*
X106800Y333346D01*
Y339700D01*
X111500Y344400D01*
Y352710D01*
X114800Y356010D01*
Y362770D01*
X115150Y363120D01*
Y366907D01*
X118145Y369902D01*
X119421D01*
X120130Y370611D01*
Y371613D01*
X119421Y372322D01*
X115920D01*
X115500Y372742D01*
Y374917D01*
X115920Y375337D01*
X122621D01*
X123330Y376046D01*
Y377048D01*
X122621Y377757D01*
X115920D01*
X115500Y378177D01*
Y385530D01*
X117470Y387500D01*
X124460D01*
X126340Y385620D01*
Y382700D01*
G01X148041Y426700D02*
X146781Y427960D01*
X122704D01*
X120484Y425740D01*
X116700D01*
X115110Y424150D01*
Y415610D01*
X113890Y414390D01*
X101410D01*
X99348Y416452D01*
X79552D01*
X77592Y414492D01*
Y413437D01*
G01X189766Y432050D02*
X191700Y433984D01*
Y435800D01*
X190030Y437470D01*
X165443D01*
X161915Y433942D01*
Y427318D01*
X167680Y421553D01*
Y414487D01*
X159860Y406667D01*
Y402395D01*
X153438Y395973D01*
X151216D01*
X134240Y378997D01*
Y367439D01*
X129870Y363069D01*
Y359709D01*
X126210Y356049D01*
Y344550D01*
X125150Y343490D01*
X122579D01*
X118820Y339731D01*
Y331342D01*
X114110Y326632D01*
Y322389D01*
X109550Y317829D01*
Y307456D01*
X107620Y305526D01*
X105964Y304840D01*
X104608D01*
X98890Y299122D01*
Y293202D01*
X88850Y283162D01*
Y281817D01*
X87050Y280017D01*
Y265156D01*
X87670Y264536D01*
Y256928D01*
X88280Y256318D01*
Y254307D01*
X88170Y254197D01*
Y251603D01*
X88280Y251493D01*
Y248714D01*
X88060Y248494D01*
Y240459D01*
X85160Y237559D01*
Y231959D01*
X79800Y226599D01*
Y200640D01*
X78700Y197983D01*
Y191118D01*
X82290Y182450D01*
Y180122D01*
X86008Y171147D01*
X106040Y151115D01*
Y148860D01*
X112600Y142300D01*
Y135046D01*
X115612Y127774D01*
X117496Y125890D01*
Y122202D01*
X118100Y121598D01*
Y113005D01*
X116920Y111825D01*
Y103822D01*
X121149Y99593D01*
X131817D01*
X138210Y93200D01*
X152100D01*
X157500Y87800D01*
X173200D01*
X179000Y93600D01*
X191100D01*
X196400Y98900D01*
Y106166D01*
X201267Y111033D01*
X203967D01*
X207734Y114800D01*
X211900D01*
X213400Y116300D01*
Y120100D01*
X215270Y121970D01*
X226937D01*
X228620Y123653D01*
Y125958D01*
X232056Y129394D01*
X233311D01*
X233511Y129594D01*
G01X229342Y129240D02*
Y128642D01*
X227300Y126600D01*
Y124200D01*
X226390Y123290D01*
X214357D01*
X204184Y113117D01*
X201484D01*
X194900Y106533D01*
Y100400D01*
X189600Y95100D01*
X178000D01*
X172300Y89400D01*
X158100D01*
X152800Y94700D01*
X139410D01*
X133062Y101048D01*
X121703D01*
X118445Y104306D01*
Y110093D01*
X124209Y115857D01*
Y117590D01*
X122482Y119317D01*
X122248D01*
X118816Y122749D01*
Y126437D01*
X116806Y128447D01*
X113920Y135414D01*
Y142847D01*
X107360Y149407D01*
Y151700D01*
X87101Y171959D01*
X83610Y180387D01*
Y191320D01*
X80100Y194830D01*
Y197634D01*
X81120Y200097D01*
Y225386D01*
X89380Y233646D01*
Y247947D01*
X89600Y248167D01*
Y252040D01*
X89490Y252150D01*
Y253650D01*
X89600Y253760D01*
Y256865D01*
X88990Y257475D01*
Y265083D01*
X88370Y265703D01*
Y279470D01*
X90170Y281270D01*
Y282615D01*
X99345Y291790D01*
X101450D01*
X102510Y292850D01*
Y298850D01*
X102509Y298851D01*
Y299943D01*
X102510Y299944D01*
Y300875D01*
X105155Y303520D01*
X106227D01*
X108368Y304407D01*
X110870Y306909D01*
Y317282D01*
X115431Y321843D01*
Y322935D01*
X115430Y322936D01*
Y326085D01*
X120140Y330795D01*
Y339095D01*
X123215Y342170D01*
X126298D01*
X127530Y343402D01*
Y355502D01*
X131190Y359162D01*
Y362522D01*
X135560Y366892D01*
Y378450D01*
X151763Y394653D01*
X153985D01*
X161180Y401848D01*
Y406120D01*
X169000Y413940D01*
Y422100D01*
X163235Y427865D01*
Y433395D01*
X165730Y435890D01*
X178412D01*
X179121Y435181D01*
Y431289D01*
X179830Y430580D01*
X180832D01*
X181541Y431289D01*
Y435181D01*
X182250Y435890D01*
X188858D01*
X189838Y434910D01*
G01X217262Y129294D02*
X215027Y131529D01*
Y132584D01*
X213211Y134400D01*
X207600D01*
X206300Y133100D01*
Y124300D01*
X205000Y123000D01*
X199500D01*
X196500Y120000D01*
Y114500D01*
X189500Y107500D01*
X165500D01*
X160400Y102400D01*
X148104D01*
X142346Y108158D01*
X138942D01*
X136419Y110681D01*
Y114092D01*
X130264Y120247D01*
X129020D01*
X127518Y121749D01*
Y126279D01*
X124300Y129497D01*
Y148200D01*
X117100Y155400D01*
X112574D01*
X92442Y175532D01*
X89910Y181645D01*
Y205524D01*
X87500Y207934D01*
Y222833D01*
X95850Y231183D01*
Y239850D01*
X100200Y244200D01*
Y249794D01*
X99100Y250894D01*
Y278956D01*
X101288Y281144D01*
X102083Y283058D01*
X102405Y283834D01*
X107128Y288557D01*
X113001D01*
X114330Y289886D01*
Y299589D01*
X118520Y303779D01*
Y307119D01*
X121280Y309879D01*
Y314481D01*
X138700Y331901D01*
Y338847D01*
X141730Y341877D01*
X144678D01*
X167400Y364599D01*
Y390500D01*
X174860Y397960D01*
Y429940D01*
X173320Y431480D01*
X167770D01*
X167008Y430718D01*
G01X165500Y433100D02*
X173850D01*
X176380Y430570D01*
Y397580D01*
X168720Y389920D01*
Y358620D01*
X161740Y351640D01*
X156308D01*
X145225Y340557D01*
X142847D01*
X140020Y337730D01*
Y329682D01*
X128372Y318034D01*
Y312812D01*
X119840Y304280D01*
Y303232D01*
X115650Y299042D01*
Y289295D01*
X113574Y287219D01*
X110294D01*
X108336Y285261D01*
X105699D01*
X103524Y283086D01*
X103303Y282551D01*
X102407Y280396D01*
X100600Y278589D01*
Y251261D01*
X101520Y250341D01*
Y243653D01*
X101500Y243633D01*
Y242500D01*
X100730Y241730D01*
Y233395D01*
X93140Y225805D01*
Y221940D01*
X88820Y217620D01*
Y208680D01*
X91230Y206270D01*
Y181908D01*
X93561Y176281D01*
X106442Y163400D01*
X114300D01*
X117600Y160100D01*
Y157030D01*
X125800Y148830D01*
Y129865D01*
X133660Y122005D01*
Y118724D01*
X137739Y114645D01*
Y111229D01*
X139490Y109478D01*
X142893D01*
X148251Y104120D01*
X160053D01*
X164753Y108820D01*
X188881D01*
X195000Y114939D01*
Y121099D01*
X201900Y127999D01*
Y133300D01*
X204369Y135769D01*
X221809D01*
X225284Y132294D01*
G01X212757Y127064D02*
Y126056D01*
X207000Y120299D01*
X199799D01*
X197900Y118400D01*
Y113599D01*
X190481Y106180D01*
X169580D01*
X164340Y100940D01*
X147561D01*
X146760Y101741D01*
X138233D01*
X135099Y104875D01*
Y113471D01*
X129948Y118622D01*
X128778D01*
X126198Y121202D01*
Y125732D01*
X122800Y129130D01*
Y147159D01*
X122323Y148310D01*
X116553Y154080D01*
X112027D01*
X91322Y174785D01*
X88590Y181381D01*
Y204977D01*
X86100Y207467D01*
Y223300D01*
X94530Y231730D01*
Y240863D01*
X98720Y245053D01*
Y248907D01*
X96770Y250857D01*
Y261167D01*
X95367Y262570D01*
Y264070D01*
X97720Y266423D01*
Y279443D01*
X100169Y281892D01*
X100863Y283564D01*
X101285Y284581D01*
X106646Y289942D01*
X112044D01*
X113010Y290908D01*
Y300136D01*
X117200Y304326D01*
Y307740D01*
X119530Y310070D01*
X119920Y311011D01*
Y315420D01*
X127800Y323300D01*
Y329544D01*
X131410Y333154D01*
Y334838D01*
X134072Y337500D01*
X135486D01*
X141183Y343197D01*
X143668D01*
X155144Y354673D01*
Y370356D01*
X147000Y378500D01*
Y386066D01*
X152947Y392013D01*
X157337D01*
X159478Y389872D01*
X160272D01*
X160836Y390436D01*
Y391230D01*
X158695Y393371D01*
Y394165D01*
X159259Y394729D01*
X160053D01*
X161994Y392788D01*
X162888D01*
X163452Y393352D01*
Y394046D01*
X161411Y396087D01*
Y396881D01*
X161975Y397445D01*
X162769D01*
X164910Y395304D01*
X165704D01*
X166268Y395868D01*
Y396662D01*
X164127Y398803D01*
Y399597D01*
X172530Y408000D01*
Y420950D01*
G01X167865Y427771D02*
X170600Y425036D01*
Y413700D01*
X170320Y413420D01*
Y413393D01*
X162500Y405573D01*
Y401301D01*
X154532Y393333D01*
X152310D01*
X136880Y377903D01*
Y358479D01*
X132021Y353620D01*
X130353D01*
X128850Y352117D01*
Y342855D01*
X126845Y340850D01*
X123762D01*
X121760Y338848D01*
Y330548D01*
X116800Y325588D01*
Y321345D01*
X112190Y316735D01*
Y306362D01*
X109116Y303288D01*
X106490Y302200D01*
X105702D01*
X103830Y300328D01*
Y292303D01*
X101997Y290470D01*
X99892D01*
X94110Y284688D01*
Y281350D01*
X93050Y280290D01*
X91057D01*
X89690Y278923D01*
Y266250D01*
X91707Y264233D01*
Y260393D01*
X93110Y258990D01*
Y249810D01*
X90700Y247400D01*
Y233099D01*
X82440Y224839D01*
Y205606D01*
X84930Y203116D01*
Y180650D01*
X88220Y172707D01*
X108680Y152247D01*
Y149954D01*
X115240Y143394D01*
Y135684D01*
X117929Y129191D01*
X118816Y128304D01*
X119892D01*
X123558Y124638D01*
Y120108D01*
X127066Y116600D01*
Y113568D01*
X132459Y108175D01*
Y103531D01*
X137022Y98968D01*
X145583D01*
X146251Y98300D01*
X173400D01*
X174900Y96800D01*
X189300D01*
X193200Y100700D01*
Y106700D01*
X201690Y115190D01*
X204390D01*
X216684Y127484D01*
X218012D01*
X219072Y128544D01*
Y130484D01*
X217262Y132294D01*
G01X176300Y98700D02*
X175380Y99620D01*
X146870D01*
X146170Y100320D01*
X137715D01*
X133779Y104256D01*
Y109142D01*
X128866Y114055D01*
Y116667D01*
X124878Y120655D01*
Y125185D01*
X121400Y128663D01*
Y140642D01*
X111020Y151022D01*
Y153217D01*
X90205Y174032D01*
X87270Y181118D01*
Y204430D01*
X84780Y206920D01*
Y223869D01*
X93130Y232219D01*
Y241330D01*
X97400Y245600D01*
Y248360D01*
X95450Y250310D01*
Y260620D01*
X94047Y262023D01*
Y264618D01*
X96400Y266971D01*
Y279990D01*
X99050Y282640D01*
X100166Y285329D01*
X106170Y291333D01*
Y297032D01*
X114530Y305392D01*
Y315765D01*
X119500Y320735D01*
Y324978D01*
X128770Y334248D01*
Y337170D01*
X131190Y339590D01*
Y347390D01*
X132080Y348280D01*
X133350D01*
X136350Y351280D01*
X145523D01*
X148743Y354500D01*
X151200D01*
X151700Y355000D01*
Y357895D01*
X151695Y357900D01*
G01X118692Y137304D02*
Y141907D01*
X110000Y150599D01*
Y152794D01*
X89340Y173454D01*
X86250Y180914D01*
Y203663D01*
X83760Y206153D01*
Y224292D01*
X92020Y232552D01*
Y246380D01*
X94430Y248790D01*
Y259537D01*
X93027Y260940D01*
Y265041D01*
X95380Y267394D01*
Y280413D01*
X95600Y280633D01*
Y284311D01*
X100439Y289150D01*
X102544D01*
X105150Y291756D01*
Y297455D01*
X113510Y305815D01*
Y316188D01*
X118200Y320878D01*
Y325121D01*
X123080Y330001D01*
Y338301D01*
X124309Y339530D01*
X127392D01*
X130170Y342308D01*
Y351570D01*
X130900Y352300D01*
X145100D01*
X149500Y356700D01*
G01X184729Y115820D02*
Y111809D01*
X183220Y110300D01*
X164366D01*
X159506Y105440D01*
X148798D01*
X143440Y110798D01*
X140187D01*
X139059Y111926D01*
Y115192D01*
X135150Y119101D01*
Y122382D01*
X127300Y130232D01*
Y149297D01*
X119095Y157502D01*
Y160605D01*
X114400Y165300D01*
X106420D01*
X94674Y177046D01*
X92900Y181327D01*
Y206600D01*
X90140Y209360D01*
Y216580D01*
X94460Y220900D01*
Y225258D01*
X106170Y236968D01*
Y241630D01*
X102840Y244960D01*
Y250888D01*
X101920Y251808D01*
Y256319D01*
X104600Y258999D01*
Y271206D01*
X103950Y271856D01*
Y275544D01*
X104600Y276194D01*
Y276195D01*
X106555Y278150D01*
X106556D01*
X106557Y278151D01*
X107649D01*
X107650Y278150D01*
X108500D01*
X109700Y279350D01*
Y284757D01*
X110825Y285882D01*
X114123D01*
X116970Y288729D01*
Y298495D01*
X121160Y302685D01*
Y303733D01*
X129692Y312265D01*
Y317487D01*
X144205Y332000D01*
X150800D01*
X153419Y334619D01*
Y341978D01*
G01X120200Y361600D02*
X118530Y359930D01*
Y347236D01*
X113246Y341952D01*
X112953D01*
X112952Y341951D01*
X112908D01*
X109950Y338993D01*
Y330117D01*
X108212Y328379D01*
Y327430D01*
X105039Y324257D01*
Y323239D01*
X97620Y315820D01*
Y303453D01*
X94560Y300393D01*
Y294473D01*
X91687Y291600D01*
X88668D01*
X82230Y285162D01*
Y280692D01*
X81030Y277793D01*
Y273403D01*
X79720Y272093D01*
Y264904D01*
X80567Y264057D01*
Y262040D01*
X80514Y261912D01*
Y255818D01*
X83430Y252902D01*
Y247030D01*
X80300Y243900D01*
Y243700D01*
G01X131540Y394690D02*
Y387848D01*
X128150Y384458D01*
Y382337D01*
X127632Y381086D01*
X124650Y378104D01*
Y372302D01*
X120930Y368582D01*
X118692D01*
X116900Y366790D01*
Y362727D01*
X116190Y362017D01*
Y355251D01*
X112800Y351861D01*
Y343710D01*
X108630Y339540D01*
Y333309D01*
X103650Y328329D01*
Y327010D01*
X101190Y324550D01*
Y321489D01*
X96300Y316599D01*
Y304000D01*
X93240Y300940D01*
Y295837D01*
X90923Y293520D01*
G01X283500Y89500D02*
X280100Y86100D01*
X269400D01*
X262700Y79400D01*
X248439D01*
X235349Y66310D01*
X222510D01*
X221100Y64900D01*
X202200D01*
X185000Y47700D01*
X153600D01*
X148000Y53300D01*
X139200D01*
X133695Y47795D01*
Y45527D01*
X129677Y41509D01*
X124960D01*
X120005Y46464D01*
X110126D01*
X105890Y50700D01*
X104799D01*
X104600Y50501D01*
G01X158246Y78872D02*
X154728Y82390D01*
X143369D01*
X142969Y81990D01*
X134760D01*
X132170Y79400D01*
X125909D01*
X124490Y77981D01*
X122989D01*
X121900Y79070D01*
Y86900D01*
X122000Y87000D01*
Y95215D01*
X113215Y104000D01*
Y110548D01*
X113220Y110553D01*
Y119247D01*
X113215Y119252D01*
Y119685D01*
X107390Y125510D01*
Y129250D01*
X107700Y129560D01*
Y138060D01*
X108270Y138630D01*
G01X182865Y113706D02*
X182000Y112841D01*
Y112200D01*
X181500Y111700D01*
X163899D01*
X158959Y106760D01*
X149359D01*
X136470Y119649D01*
Y122929D01*
X128700Y130699D01*
Y149900D01*
X124100Y154500D01*
Y158900D01*
X119500Y163500D01*
Y196695D01*
X117250Y198945D01*
Y200445D01*
X119500Y202695D01*
Y210031D01*
X118899Y210632D01*
Y215447D01*
X116621Y220945D01*
X109321Y228245D01*
Y232972D01*
X109070Y233223D01*
Y236476D01*
X107820Y237726D01*
Y247921D01*
X109490Y249591D01*
Y256050D01*
X114000Y260560D01*
Y262909D01*
X112860Y265663D01*
Y269133D01*
X111423Y270570D01*
X107103D01*
X105270Y272403D01*
Y274997D01*
X105920Y275647D01*
Y275648D01*
X107102Y276830D01*
X109047D01*
X111020Y278803D01*
Y280772D01*
X118790Y288542D01*
Y294990D01*
X121584Y297784D01*
X122784D01*
X124910Y299910D01*
Y304954D01*
X131012Y311056D01*
Y316492D01*
X145200Y330680D01*
X151347D01*
X155910Y335243D01*
Y348460D01*
X157770Y350320D01*
X162287D01*
X170040Y358073D01*
Y389373D01*
X177700Y397033D01*
Y419139D01*
X184809Y426248D01*
X185352Y427264D01*
X184480Y429370D01*
G01X171600Y114000D02*
Y115680D01*
X171180Y116100D01*
X166400D01*
X158380Y108080D01*
X149906D01*
X139059Y118927D01*
Y122400D01*
X137000Y124459D01*
Y128700D01*
X130020Y135680D01*
Y150480D01*
X128500Y152000D01*
Y158700D01*
X127000Y160200D01*
X125000D01*
X120900Y164300D01*
Y210498D01*
X120219Y211179D01*
Y215710D01*
X117742Y221691D01*
X110641Y228792D01*
Y233519D01*
X110390Y233770D01*
Y237023D01*
X109140Y238273D01*
Y247374D01*
X113305Y251539D01*
Y255876D01*
X115840Y258411D01*
Y261962D01*
X114180Y265973D01*
Y269680D01*
X111970Y271890D01*
X107650D01*
X106590Y272950D01*
Y274450D01*
X107650Y275510D01*
X109777D01*
X125200Y290933D01*
Y298333D01*
X126230Y299363D01*
Y304407D01*
X132332Y310509D01*
Y315945D01*
X145647Y329260D01*
X151794D01*
X161100Y338566D01*
Y345738D01*
X171360Y355998D01*
Y388826D01*
X179021Y396487D01*
Y397579D01*
X179020Y397580D01*
Y418591D01*
X187180Y426751D01*
Y428720D01*
X186720Y429831D01*
Y432490D01*
G01X133500Y409110D02*
Y406300D01*
X130690Y403490D01*
Y399250D01*
X132028Y397912D01*
X133638D01*
X136770Y394780D01*
Y389226D01*
X130790Y383246D01*
Y381810D01*
X129870Y379590D01*
X127460Y377180D01*
Y366260D01*
X125910Y364710D01*
Y361350D01*
X119850Y355290D01*
Y346689D01*
X113792Y340631D01*
X113455D01*
X111270Y338446D01*
Y329570D01*
X109532Y327832D01*
Y323412D01*
X103190Y317070D01*
Y310010D01*
X103900Y309300D01*
X105100D01*
G01X97800Y325700D02*
Y332000D01*
X100552Y334752D01*
Y337394D01*
X109600Y346442D01*
Y356700D01*
X108520Y357780D01*
Y389120D01*
X121700Y402300D01*
Y407900D01*
X120400Y409200D01*
X118932D01*
X116632Y411500D01*
G01X133070Y420874D02*
X129874D01*
X125840Y416840D01*
Y408293D01*
X126680Y407453D01*
Y405413D01*
X112780Y391513D01*
Y374679D01*
X109340Y371239D01*
Y364910D01*
X110650Y363600D01*
X112550D01*
X113430Y362720D01*
Y356930D01*
X110500Y354000D01*
Y345474D01*
X103180Y338154D01*
Y336286D01*
G01X156200Y111600D02*
Y110500D01*
X155100Y109400D01*
X151300D01*
X145500Y115200D01*
Y123900D01*
X142100Y127300D01*
Y130600D01*
X138400Y134300D01*
Y140200D01*
X133800Y144800D01*
X132100D01*
X131600Y145300D01*
Y150800D01*
X130000Y152400D01*
Y159100D01*
X126900Y162200D01*
X125300D01*
X122400Y165100D01*
Y169600D01*
X122900Y170100D01*
G01X112200Y234520D02*
X111961Y234281D01*
Y229339D01*
X118863Y222437D01*
X120653Y218115D01*
X125268Y213500D01*
Y212197D01*
X122220Y209149D01*
Y173852D01*
X126310Y169762D01*
Y167090D01*
X131520Y161880D01*
Y157280D01*
X135310Y153490D01*
Y145157D01*
X140600Y139867D01*
Y136100D01*
X144300Y132400D01*
Y127500D01*
X147000Y124800D01*
Y120435D01*
X148663Y118772D01*
Y118063D01*
X147600Y117000D01*
G01X190370Y422490D02*
X184787D01*
X180340Y418043D01*
Y398127D01*
X180341Y398126D01*
Y395940D01*
X173952Y389551D01*
Y341518D01*
X169984Y337550D01*
X161951D01*
X152341Y327940D01*
X146290D01*
X133652Y315302D01*
Y309962D01*
X127550Y303860D01*
Y298816D01*
X126520Y297786D01*
Y290386D01*
X113110Y276976D01*
Y272989D01*
X115500Y270599D01*
Y266283D01*
X115982Y265119D01*
X117160Y263941D01*
Y257864D01*
X114625Y255329D01*
Y250992D01*
X110460Y246827D01*
Y238820D01*
X114010Y235270D01*
Y233610D01*
X113361Y232961D01*
Y229806D01*
X119982Y223185D01*
X121773Y218862D01*
X126588Y214047D01*
Y205056D01*
X126851Y203733D01*
X127963Y201037D01*
Y198329D01*
X123848Y194214D01*
Y174091D01*
X129370Y168569D01*
Y166003D01*
X131203Y164170D01*
X133112D01*
X138000Y159282D01*
Y154000D01*
X136630Y152630D01*
Y145704D01*
X141134Y141200D01*
X144000D01*
X147800Y137400D01*
Y130601D01*
X151461Y126940D01*
X153007Y123210D01*
X153332Y122992D01*
X156222Y120102D01*
X157980D01*
X158525Y119876D01*
X160847Y117554D01*
Y116547D01*
X161907Y115487D01*
X163407D01*
X165720Y117800D01*
X175000D01*
X176340Y119140D01*
X180860D01*
X181500Y118500D01*
Y117700D01*
X182000Y117200D01*
G01X187069Y116800D02*
X185429Y118440D01*
X184600D01*
X182580Y120460D01*
X175793D01*
X174453Y119120D01*
X163803D01*
X158243Y121422D01*
X156769D01*
X154174Y124017D01*
X154074Y124084D01*
X152018Y129047D01*
Y138882D01*
X150800Y140100D01*
X147958D01*
X143960Y144098D01*
Y146652D01*
X142600Y148012D01*
Y148565D01*
X141459Y149706D01*
Y151206D01*
X142600Y152347D01*
Y156549D01*
X133659Y165490D01*
X131750D01*
X130690Y166550D01*
Y170610D01*
X128310Y172990D01*
Y183650D01*
X126400Y185560D01*
Y194899D01*
X129283Y197782D01*
Y201661D01*
X127987Y204789D01*
X127908Y205187D01*
Y214594D01*
X122893Y219609D01*
X121101Y223933D01*
X118997Y226037D01*
Y232433D01*
X114710Y236720D01*
Y239950D01*
X111780Y242880D01*
Y246280D01*
X115945Y250445D01*
Y254782D01*
X119700Y258537D01*
Y269643D01*
X116940Y272403D01*
Y278939D01*
X127840Y289839D01*
Y297239D01*
X128870Y298269D01*
Y303272D01*
X137440Y311842D01*
Y314007D01*
X150053Y326620D01*
X154388D01*
X163998Y336230D01*
X170532D01*
X175272Y340970D01*
Y389004D01*
X181661Y395393D01*
Y398673D01*
X181660Y398674D01*
Y417496D01*
X184164Y420000D01*
X191200D01*
X193740Y422540D01*
X195000D01*
G01X195983Y132294D02*
X198150Y130127D01*
Y128130D01*
X191800Y121780D01*
X175246D01*
X173906Y120440D01*
X164068D01*
X161855Y121356D01*
X159021Y125596D01*
X157488Y127129D01*
X156251D01*
X154976Y127981D01*
X154862Y128257D01*
X154114Y129005D01*
Y132589D01*
X155615Y134090D01*
Y135608D01*
X156232Y137097D01*
X157770Y138635D01*
Y139940D01*
X156288Y141422D01*
X148503D01*
X145280Y144645D01*
Y147199D01*
X145270Y147209D01*
Y155746D01*
X141850Y159166D01*
Y161651D01*
X130680Y172821D01*
Y173920D01*
X129630Y174970D01*
Y184197D01*
X127720Y186107D01*
Y194352D01*
X130603Y197235D01*
Y201924D01*
X129257Y205175D01*
X129230Y205311D01*
Y215139D01*
X124015Y220354D01*
X122222Y224679D01*
X120493Y226408D01*
Y233037D01*
X119390Y234140D01*
Y235640D01*
X120110Y236360D01*
Y238250D01*
X119800Y238560D01*
Y245884D01*
X117265Y248419D01*
Y254235D01*
X121060Y258030D01*
Y261561D01*
X124260Y264761D01*
Y266950D01*
X118260Y272950D01*
Y278392D01*
X129160Y289292D01*
Y296692D01*
X130190Y297722D01*
Y302725D01*
X138760Y311295D01*
Y313460D01*
X150600Y325300D01*
X158050D01*
X165530Y332780D01*
X169180D01*
X176800Y340400D01*
Y345700D01*
X184600Y353500D01*
Y363100D01*
X189260Y367760D01*
Y385340D01*
X186480Y388120D01*
Y393220D01*
X184200Y395500D01*
Y409400D01*
X187735Y412935D01*
Y413635D01*
X194700Y420600D01*
X196840D01*
X199940Y423700D01*
G01X236221Y454400D02*
X232248D01*
X230162Y453536D01*
X228292Y451666D01*
X221275D01*
X220563Y450954D01*
Y448412D01*
X219851Y447700D01*
X218845D01*
X218133Y448412D01*
Y450954D01*
X217421Y451666D01*
X216639D01*
X210369Y449069D01*
X208930Y447630D01*
Y441430D01*
X205300Y437800D01*
Y437043D01*
X205280Y437023D01*
Y434279D01*
X202020Y431019D01*
Y422619D01*
X198681Y419280D01*
X195247D01*
X189055Y413088D01*
Y412388D01*
X185520Y408853D01*
Y396047D01*
X187800Y393767D01*
Y388701D01*
X190580Y385921D01*
Y367002D01*
X185920Y362342D01*
Y352920D01*
X178120Y345120D01*
Y339853D01*
X169727Y331460D01*
X166077D01*
X158597Y323980D01*
X155160D01*
X150370Y319190D01*
X146357D01*
X140080Y312913D01*
Y310748D01*
X131510Y302178D01*
Y297175D01*
X130480Y296145D01*
Y288745D01*
X129600Y287865D01*
Y287864D01*
X121970Y280234D01*
Y272263D01*
X125580Y268653D01*
Y264214D01*
X122380Y261014D01*
Y251085D01*
X124837Y248628D01*
Y235635D01*
X126700Y233772D01*
Y222980D01*
X126200Y221773D01*
Y220036D01*
X130550Y215686D01*
Y205510D01*
X132000Y202010D01*
Y173368D01*
X143170Y162198D01*
Y159713D01*
X146590Y156293D01*
Y147756D01*
X146600Y147746D01*
Y145192D01*
X148850Y142942D01*
X156918D01*
X159290Y140570D01*
Y138005D01*
X157574Y136289D01*
X157135Y135229D01*
Y133035D01*
X159080Y131090D01*
Y128245D01*
X163064Y122285D01*
X164332Y121760D01*
X173359D01*
X174699Y123100D01*
X179590D01*
X185178Y128688D01*
X187435Y129623D01*
G01X108551Y294241D02*
Y297546D01*
X115850Y304845D01*
Y315218D01*
X121000Y320368D01*
Y324611D01*
X130090Y333701D01*
Y336391D01*
X132510Y338811D01*
Y345573D01*
X136897Y349960D01*
X146070D01*
X149290Y353180D01*
X151747D01*
X153824Y355257D01*
Y369809D01*
X151123Y372510D01*
X139200D01*
G01X114700Y348500D02*
X117510Y351310D01*
Y361470D01*
X118220Y362180D01*
Y366243D01*
X119239Y367262D01*
X121477D01*
X123247Y369032D01*
X123248D01*
X125970Y371754D01*
Y377557D01*
X128751Y380338D01*
X129470Y382074D01*
Y383793D01*
X135450Y389773D01*
Y394233D01*
X133091Y396592D01*
X131480D01*
X129370Y398702D01*
Y404037D01*
X131580Y406247D01*
Y409940D01*
X132300Y410660D01*
Y414414D01*
X134300Y416414D01*
G01X111869Y365454D02*
Y366787D01*
X114100Y372174D01*
Y390966D01*
X128000Y404866D01*
Y408000D01*
X127160Y408840D01*
Y416293D01*
X129867Y419000D01*
X155080D01*
Y419047D01*
X157955Y421922D01*
Y430528D01*
X154160Y434323D01*
Y436917D01*
X155220Y437977D01*
Y437987D01*
X155993Y438760D01*
X158963D01*
X159300Y439097D01*
Y441500D01*
X158100Y442700D01*
G01X109048Y425853D02*
X110554Y427359D01*
Y427360D01*
X119812D01*
X122032Y429580D01*
X137772D01*
X139192Y431000D01*
X146400D01*
X150200Y427200D01*
Y425040D01*
X151350Y423890D01*
X151410D01*
X152200Y423100D01*
G01X119500Y433600D02*
X121700Y435800D01*
X139176D01*
X146476Y443100D01*
X153300D01*
X156800Y446600D01*
Y447500D01*
X158207Y448907D01*
X159397Y449400D01*
X159400D01*
Y449408D01*
X159396D01*
G01X239500Y447750D02*
X231050Y439300D01*
X228399D01*
X222750Y433651D01*
Y418150D01*
X217700Y413100D01*
X214192D01*
X213629Y413663D01*
Y421057D01*
X213066Y421620D01*
X212271D01*
X211708Y421057D01*
Y413663D01*
X208679Y410634D01*
X205880D01*
X205380Y410134D01*
Y401150D01*
X207960Y398570D01*
Y388823D01*
X210560Y386223D01*
Y382977D01*
X202600Y375017D01*
Y347231D01*
X199623Y340046D01*
X193327Y333750D01*
X189879D01*
X186459Y330330D01*
X185000D01*
X182770Y328100D01*
X180768D01*
X175448Y322780D01*
X172680D01*
X166400Y316500D01*
Y314000D01*
X164530Y312130D01*
Y306031D01*
X162426Y303927D01*
X158327D01*
X146935Y292535D01*
X146203D01*
X144370Y290702D01*
Y289970D01*
X139180Y284780D01*
Y274376D01*
X138955Y273833D01*
X138665Y273399D01*
X135420Y270154D01*
Y261120D01*
X130710Y256410D01*
Y240484D01*
X134870Y236324D01*
Y233141D01*
X132010Y230281D01*
Y225492D01*
X134141Y223361D01*
X135638D01*
X136810Y222189D01*
Y219510D01*
X136290Y218990D01*
Y210037D01*
X138590Y207737D01*
Y205823D01*
X137280Y204513D01*
Y190220D01*
X145070Y182430D01*
Y176230D01*
X149640Y171660D01*
Y163964D01*
X150750Y162854D01*
Y161577D01*
X154290Y158037D01*
Y155207D01*
X165348Y144149D01*
Y140710D01*
X172558Y133500D01*
Y131428D01*
X171774Y129536D01*
X170867Y128629D01*
Y128211D01*
G01X205223Y422665D02*
X204065D01*
X199360Y417960D01*
X195794D01*
X193900Y416066D01*
Y409178D01*
X186840Y402118D01*
Y396594D01*
X188034Y395400D01*
X190096D01*
X192310Y393186D01*
Y391354D01*
X191900Y390944D01*
Y366455D01*
X187240Y361795D01*
Y351839D01*
X179440Y344039D01*
Y339306D01*
X170274Y330140D01*
X166624D01*
X153844Y317360D01*
X147761D01*
X144700Y314299D01*
Y310819D01*
X142641Y308760D01*
X139959D01*
X132830Y301631D01*
Y296628D01*
X131800Y295598D01*
Y288198D01*
X130920Y287318D01*
Y287317D01*
X123290Y279687D01*
Y272810D01*
X126900Y269200D01*
Y263667D01*
X123700Y260467D01*
Y251632D01*
X126157Y249175D01*
Y236182D01*
X128020Y234319D01*
Y222820D01*
X128050Y222790D01*
Y220053D01*
X131870Y216233D01*
Y205777D01*
X133320Y202277D01*
Y188579D01*
X141110Y180789D01*
Y174089D01*
X142690Y172509D01*
Y166210D01*
X144490Y164410D01*
Y160260D01*
X147175Y157575D01*
X149150D01*
X150210Y156515D01*
Y153403D01*
X160810Y142803D01*
Y132930D01*
X160400Y132520D01*
Y129006D01*
X162737Y125511D01*
X165168Y123080D01*
X170772D01*
X174189Y126497D01*
X177218Y127752D01*
X178290Y128824D01*
G01X235200Y449100D02*
Y447184D01*
X230116Y442100D01*
X227399D01*
X218899Y433600D01*
Y433535D01*
X205176Y419812D01*
X203296D01*
X200995Y417511D01*
Y413500D01*
X202090Y412405D01*
Y400140D01*
X204920Y397310D01*
Y381637D01*
X199480Y376197D01*
Y365928D01*
X199060Y365508D01*
X192820D01*
X188560Y361248D01*
Y351292D01*
X186100Y348832D01*
Y342463D01*
X172457Y328820D01*
X167171D01*
X152034Y313683D01*
X149482D01*
X143239Y307440D01*
X140566D01*
X134150Y301024D01*
Y296081D01*
X133120Y295051D01*
Y287651D01*
X132500Y287031D01*
Y287030D01*
X126950Y281480D01*
Y272951D01*
X128010Y271891D01*
X129510D01*
X131280Y270121D01*
Y264336D01*
X128544Y261600D01*
X126700D01*
X125020Y259920D01*
Y252179D01*
X127477Y249722D01*
Y239983D01*
X132230Y235230D01*
Y234235D01*
X129370Y231375D01*
Y220601D01*
X133190Y216781D01*
Y206309D01*
X134640Y202805D01*
Y189126D01*
X142430Y181336D01*
Y174636D01*
X147000Y170066D01*
Y162870D01*
X148110Y161760D01*
Y160483D01*
X151650Y156943D01*
Y153830D01*
X162440Y143040D01*
Y134229D01*
X164901Y131768D01*
Y125399D01*
X165900Y124400D01*
X170225D01*
X174553Y128728D01*
G01X168800Y126800D02*
Y133300D01*
X163865Y138235D01*
Y143765D01*
X152970Y154660D01*
Y157490D01*
X149430Y161030D01*
Y162307D01*
X148320Y163417D01*
Y170981D01*
X143750Y175551D01*
Y181883D01*
X135960Y189673D01*
Y205060D01*
X137270Y206370D01*
Y207190D01*
X134970Y209490D01*
Y216869D01*
X130690Y221149D01*
Y230828D01*
X133550Y233688D01*
Y235777D01*
X128797Y240530D01*
Y251603D01*
X126900Y253500D01*
Y256700D01*
X128100Y257900D01*
X129200D01*
X134100Y262800D01*
Y272000D01*
X134240Y272140D01*
Y274551D01*
X133370Y275421D01*
Y283770D01*
X135760Y286160D01*
Y293957D01*
X136790Y294987D01*
Y299689D01*
X141901Y304800D01*
X144333D01*
X144780Y305247D01*
X161879D01*
X163210Y306578D01*
Y309950D01*
X159900Y313260D01*
Y315357D01*
X168643Y324100D01*
X174901D01*
X180221Y329420D01*
X182223D01*
X187873Y335070D01*
X192780D01*
X198504Y340794D01*
X201000Y346821D01*
Y375567D01*
X206440Y381007D01*
Y397940D01*
X204000Y400380D01*
Y410671D01*
X206150Y412821D01*
G01X156481Y155933D02*
X156191Y156223D01*
Y163269D01*
X155470Y163990D01*
Y179230D01*
X152100Y182600D01*
X148971D01*
X143486Y188085D01*
Y189585D01*
X143530Y189629D01*
Y191129D01*
X146700Y194299D01*
Y195600D01*
X145890Y196410D01*
Y204675D01*
X144991Y205574D01*
X142709D01*
X142000Y206283D01*
Y207285D01*
X142709Y207994D01*
X144991D01*
X145700Y208703D01*
Y209510D01*
X139950Y215260D01*
Y223287D01*
X138614Y224623D01*
Y236688D01*
X134820Y240482D01*
Y253493D01*
X136830Y255503D01*
Y258154D01*
X136740Y258244D01*
Y269606D01*
X139754Y272620D01*
X140500Y273736D01*
Y279640D01*
X150690Y289830D01*
Y290175D01*
X151750Y291235D01*
X153335D01*
X158616Y296516D01*
X163236Y298435D01*
X165200Y300399D01*
Y302967D01*
X167170Y304937D01*
Y310336D01*
X170904Y314070D01*
X172263D01*
X174330Y316137D01*
Y316163D01*
X175067Y316900D01*
X179299D01*
X179780Y317381D01*
Y318383D01*
X178734Y319430D01*
Y320432D01*
X179444Y321142D01*
X180446D01*
X181492Y320095D01*
X182494D01*
X184600Y322201D01*
Y326604D01*
X190426Y332430D01*
X193874D01*
X200742Y339298D01*
X203920Y346968D01*
Y347970D01*
X204200Y348250D01*
Y374467D01*
X212080Y382347D01*
Y386853D01*
X209480Y389453D01*
Y399200D01*
X206700Y401980D01*
Y405196D01*
X207510Y406006D01*
Y408657D01*
X207539Y408686D01*
G01X162200Y158200D02*
X159299D01*
X157511Y159988D01*
Y163816D01*
X156790Y164537D01*
Y179777D01*
X151815Y184752D01*
Y186030D01*
X151241Y186604D01*
Y193560D01*
X149717Y195084D01*
Y200896D01*
X147450Y206364D01*
Y215044D01*
X149294Y216888D01*
Y228439D01*
X136140Y241593D01*
Y252946D01*
X138178Y254984D01*
X138150Y255013D01*
Y269149D01*
X141358Y272357D01*
X141820Y273473D01*
Y278515D01*
X150920Y287615D01*
X153250D01*
X154310Y288675D01*
Y289011D01*
X161398Y296099D01*
X168558D01*
X179940Y307481D01*
Y314390D01*
X193590Y328040D01*
Y330279D01*
X201861Y338550D01*
X203145Y341645D01*
X205600Y344100D01*
Y346347D01*
X206338Y347085D01*
X208062D01*
X208800Y347823D01*
Y348867D01*
X208062Y349605D01*
X206338D01*
X205600Y350343D01*
Y351387D01*
X206338Y352125D01*
X208062D01*
X208800Y352863D01*
Y353907D01*
X208062Y354645D01*
X206338D01*
X205600Y355383D01*
Y356427D01*
X206338Y357165D01*
X208062D01*
X208800Y357903D01*
Y358947D01*
X208062Y359685D01*
X206338D01*
X205600Y360423D01*
Y374000D01*
X213400Y381800D01*
Y382604D01*
X214138Y383342D01*
X215162D01*
X215900Y384080D01*
Y385124D01*
X215162Y385862D01*
X214138D01*
X213400Y386600D01*
Y387644D01*
X214138Y388382D01*
X215162D01*
X215900Y389120D01*
Y390164D01*
X215162Y390902D01*
X214138D01*
X210800Y394240D01*
Y399748D01*
X208586Y401962D01*
Y404480D01*
X208565Y404501D01*
G01X190965Y348090D02*
X187420Y344545D01*
Y341916D01*
X173004Y327500D01*
X167718D01*
X152581Y312363D01*
X150029D01*
X143786Y306120D01*
X141320D01*
X135470Y300270D01*
Y295534D01*
X134440Y294504D01*
Y287104D01*
X133820Y286484D01*
Y286483D01*
X128900Y281563D01*
Y276121D01*
X130570Y274451D01*
Y272698D01*
X132600Y270668D01*
Y263167D01*
X129133Y259700D01*
X127600D01*
G01X229900Y436600D02*
X230790Y437490D01*
X231253D01*
X236138Y442375D01*
X237893D01*
X248532Y435268D01*
X250600Y433200D01*
Y420191D01*
X249592Y417757D01*
X243810Y411975D01*
Y406499D01*
X231951Y394640D01*
X228379Y386018D01*
X213280Y370919D01*
Y351074D01*
X211092Y345788D01*
X205335Y340031D01*
X204099Y337054D01*
X196410Y329365D01*
Y327126D01*
X182580Y313296D01*
Y306245D01*
X169794Y293459D01*
X166519D01*
X161139Y288079D01*
X157453D01*
X155620Y286246D01*
Y283459D01*
X152721Y280560D01*
X149120D01*
X145087Y276527D01*
Y274460D01*
X143596Y270861D01*
X140800Y268065D01*
Y260890D01*
X143100Y258590D01*
Y252900D01*
X141130Y250930D01*
Y242870D01*
X145010Y238990D01*
Y236457D01*
X151934Y229533D01*
Y215794D01*
X150090Y213950D01*
Y211500D01*
X154098Y207492D01*
Y203791D01*
X154892Y201876D01*
X155720Y201048D01*
Y194271D01*
X156220Y193771D01*
Y184081D01*
X159430Y180871D01*
Y166070D01*
X165204Y160296D01*
Y157086D01*
X167201Y155089D01*
X179985D01*
X181495Y156599D01*
G01X159328Y160847D02*
X159528Y161047D01*
Y163872D01*
X158110Y165290D01*
Y180324D01*
X154900Y183534D01*
Y193224D01*
X154400Y193724D01*
Y200501D01*
X153301Y201600D01*
X151200D01*
X150610Y202190D01*
X148770Y206628D01*
Y214497D01*
X150614Y216341D01*
Y228986D01*
X143690Y235910D01*
Y238443D01*
X139810Y242323D01*
Y255220D01*
X139470Y255560D01*
Y268602D01*
X142477Y271609D01*
X143140Y273210D01*
Y276728D01*
X149170Y282758D01*
Y283870D01*
X151560Y286260D01*
X153767D01*
X156906Y289399D01*
X158839D01*
X160290Y290850D01*
Y292350D01*
X161350Y293410D01*
X163789D01*
X165158Y294779D01*
X169105D01*
X181260Y306934D01*
Y313843D01*
X194910Y327493D01*
Y329732D01*
X202980Y337802D01*
X204264Y340897D01*
X209933Y346565D01*
X210200Y347208D01*
Y373900D01*
X212100Y375800D01*
X214100D01*
X225700Y387400D01*
Y389549D01*
X232171Y405171D01*
X238100Y411100D01*
X241068D01*
X248245Y418277D01*
X249200Y420583D01*
Y432491D01*
X237727Y440157D01*
X236900Y440500D01*
Y440565D01*
G01X178346Y156599D02*
X177332D01*
X176800Y157131D01*
Y160700D01*
X175582Y161918D01*
X173092D01*
X164367Y170643D01*
Y176520D01*
X164370Y176523D01*
Y179117D01*
X164367Y179120D01*
Y183190D01*
X162914Y186698D01*
X161587Y188025D01*
X160174D01*
X158860Y189339D01*
Y201466D01*
X159597Y202203D01*
Y205703D01*
X157020Y208280D01*
Y217707D01*
X156355Y219313D01*
X154993Y220675D01*
Y230208D01*
X147650Y237551D01*
Y240450D01*
X143770Y244330D01*
Y249835D01*
X148380Y254445D01*
Y258187D01*
X146000Y260567D01*
Y269091D01*
X167728Y290819D01*
X170888D01*
X185220Y305151D01*
Y305219D01*
X185391Y305390D01*
X186650D01*
X187710Y306450D01*
Y313640D01*
X204012Y329952D01*
X207251Y337750D01*
X213172Y343908D01*
X216000Y350737D01*
Y369905D01*
X232395Y386300D01*
X234363D01*
X241560Y393497D01*
Y400515D01*
X246450Y405405D01*
Y407350D01*
X249400Y410300D01*
G01X175196Y156599D02*
X174695Y157100D01*
Y157705D01*
X171772Y160628D01*
Y161371D01*
X171352Y161791D01*
X169540D01*
X169120Y161371D01*
Y157571D01*
X168700Y157151D01*
X167006D01*
X166524Y157633D01*
Y160843D01*
X163047Y164320D01*
Y177067D01*
X163050Y177070D01*
Y178570D01*
X163047Y178573D01*
Y182485D01*
X161987Y183545D01*
X160354D01*
X157540Y186359D01*
Y202013D01*
X158277Y202750D01*
Y205022D01*
X155700Y207599D01*
Y217443D01*
X155235Y218566D01*
X153673Y220128D01*
Y229661D01*
X146330Y237004D01*
Y239900D01*
X142450Y243780D01*
Y250382D01*
X147060Y254992D01*
Y257640D01*
X144680Y260020D01*
Y269820D01*
X156940Y282080D01*
Y285699D01*
X158000Y286759D01*
X161800D01*
X167180Y292139D01*
X170341D01*
X183900Y305698D01*
Y312749D01*
X197730Y326579D01*
Y328818D01*
X205218Y336306D01*
X206454Y339283D01*
X212212Y345041D01*
X214600Y350809D01*
Y370372D01*
X229498Y385270D01*
X233071Y393893D01*
X245130Y405952D01*
Y411428D01*
X252000Y418298D01*
Y446250D01*
X249500Y448750D01*
Y455300D01*
X243800Y461000D01*
X198175D01*
X193875Y456700D01*
X191780D01*
G01X181495Y159748D02*
X180000Y161243D01*
Y162257D01*
X179985Y162272D01*
Y163524D01*
X180000Y163539D01*
Y163900D01*
X179100Y164800D01*
X173944D01*
X167010Y171734D01*
Y180211D01*
X167007Y180214D01*
Y183716D01*
X165152Y188194D01*
X164520Y188826D01*
Y191847D01*
X162237Y194130D01*
Y207064D01*
X159660Y209641D01*
Y218235D01*
X158594Y220808D01*
X157633Y221769D01*
Y231776D01*
X159190Y233333D01*
Y245934D01*
X151200Y253924D01*
Y259901D01*
X150600Y260501D01*
Y265467D01*
X154100Y268967D01*
Y273324D01*
X168955Y288179D01*
X172122D01*
X176113Y292170D01*
X182109D01*
X184180Y294241D01*
Y300081D01*
X186849Y302750D01*
X187744D01*
X190350Y305356D01*
Y312526D01*
X211280Y333495D01*
X214508Y341269D01*
X215242Y342003D01*
X218720Y350400D01*
Y366923D01*
X227797Y376000D01*
X232340D01*
X232850Y375490D01*
X234350D01*
X235700Y376840D01*
Y379215D01*
X245520Y389035D01*
Y398873D01*
X255960Y409313D01*
Y425860D01*
X261700Y431600D01*
Y439700D01*
G01X257810Y435100D02*
X253320Y430610D01*
Y417751D01*
X250540Y414971D01*
Y412100D01*
X251700Y410940D01*
Y408788D01*
X242880Y399968D01*
Y390130D01*
X233220Y380470D01*
X228432D01*
X217400Y369438D01*
Y350665D01*
X214122Y342750D01*
X208368Y336996D01*
X205131Y329204D01*
X189030Y313074D01*
Y305903D01*
X187197Y304070D01*
X186006D01*
X171435Y289499D01*
X168276D01*
X147400Y268623D01*
Y261533D01*
X149780Y259153D01*
Y249280D01*
X148600Y248100D01*
X145598D01*
X145580Y248082D01*
G01X235400Y303800D02*
Y299100D01*
X226845Y290545D01*
Y290006D01*
X225219Y288380D01*
X223257D01*
X221779Y289858D01*
X219519D01*
X219518Y289859D01*
X217558D01*
X215000Y287301D01*
Y285567D01*
X205813Y276380D01*
X202079D01*
X197140Y271441D01*
Y268209D01*
X193424Y264493D01*
X188419D01*
X186526Y262600D01*
X183034D01*
X181399Y263275D01*
X178174D01*
X175639Y260740D01*
X169790D01*
X168600Y259550D01*
Y259466D01*
X166980Y257846D01*
Y251287D01*
X168340Y249927D01*
Y227759D01*
X169270Y226829D01*
Y217570D01*
X166300Y214600D01*
Y212300D01*
G01X156970Y255000D02*
Y260690D01*
X155000Y262660D01*
Y264100D01*
X157115Y266215D01*
X157554D01*
X158600Y267261D01*
Y271778D01*
X170741Y283919D01*
X173902D01*
X177853Y287870D01*
X183838D01*
X185144Y289176D01*
X186083Y289565D01*
X187222D01*
X190600Y292943D01*
Y293840D01*
X192530Y295770D01*
X195435D01*
X195493Y295794D01*
X199360Y299661D01*
Y302769D01*
X203400Y306809D01*
Y311180D01*
X214290Y322070D01*
Y323986D01*
X220743Y330439D01*
Y340417D01*
X223210Y342884D01*
Y348609D01*
X230280Y355679D01*
Y359614D01*
X233200Y362534D01*
Y366107D01*
X237130Y370037D01*
Y372483D01*
X246847Y382200D01*
X247861D01*
X250610Y384949D01*
Y399945D01*
X259480Y408815D01*
Y419888D01*
X264503Y427408D01*
X267099Y432900D01*
X267100D01*
G01X263800Y430300D02*
X258060Y424560D01*
Y409404D01*
X247000Y398344D01*
Y388506D01*
X237420Y378926D01*
Y375688D01*
X235410Y373678D01*
Y370750D01*
X231480Y366820D01*
Y363247D01*
X223210Y354977D01*
Y351591D01*
X220270Y348651D01*
X218643Y344723D01*
Y331309D01*
X212190Y324856D01*
Y322940D01*
X201300Y312050D01*
Y308086D01*
X197700Y304486D01*
Y304079D01*
X197260Y303639D01*
Y299571D01*
X194879Y297190D01*
X191941D01*
X189180Y294429D01*
Y293780D01*
X186385Y290985D01*
X185800D01*
X184339Y290381D01*
X183288Y289330D01*
X177293D01*
X173302Y285339D01*
X170152D01*
X156100Y271287D01*
Y269329D01*
X155950Y269179D01*
Y267851D01*
X153580Y265481D01*
Y262071D01*
X154040Y261611D01*
Y254960D01*
X156378Y252622D01*
X162649D01*
X165013Y254986D01*
G01X160973D02*
X169200Y263213D01*
Y265400D01*
X176100Y272300D01*
X179612D01*
X182555Y275243D01*
X190078Y278359D01*
X195075Y283356D01*
X195737Y283630D01*
X198637D01*
X205145Y290138D01*
X206620D01*
X222560Y306078D01*
Y313144D01*
X231016Y321600D01*
X233100D01*
X238080Y326580D01*
Y331100D01*
X238705Y332613D01*
X242774Y336682D01*
Y338662D01*
X243454Y339342D01*
Y356303D01*
X259660Y372509D01*
Y394568D01*
X268270Y403178D01*
Y406258D01*
X269700Y407688D01*
Y411379D01*
G01X160590Y263300D02*
X161440Y264150D01*
Y270600D01*
X171919Y281079D01*
X175080D01*
X179031Y285030D01*
X185016D01*
X186364Y286378D01*
X187202Y286725D01*
X188331D01*
X197449Y290501D01*
X202200Y295252D01*
Y301591D01*
X206920Y306311D01*
Y310681D01*
X215619Y319380D01*
X219381D01*
X220960Y320959D01*
Y326638D01*
X223583Y329261D01*
Y338180D01*
X229097Y343694D01*
Y345488D01*
X234679Y351070D01*
X235139D01*
X237030Y352961D01*
Y358439D01*
X253450Y374859D01*
Y398766D01*
X262320Y407636D01*
Y416649D01*
X269200Y423529D01*
Y427737D01*
X274074Y439504D01*
X281725Y447155D01*
X283622D01*
G01X156970Y263250D02*
X157050D01*
X160020Y266220D01*
Y271189D01*
X171330Y282499D01*
X174491D01*
X178442Y286450D01*
X184427D01*
X185819Y287842D01*
X186550Y288145D01*
X188046D01*
X196645Y291706D01*
X200780Y295841D01*
Y302180D01*
X205500Y306900D01*
Y311271D01*
X215029Y320800D01*
X218500D01*
X219540Y321840D01*
Y327227D01*
X222163Y329850D01*
Y338769D01*
X227677Y344283D01*
Y346077D01*
X234090Y352490D01*
X234550D01*
X235610Y353550D01*
Y359029D01*
X252030Y375449D01*
Y399356D01*
X260900Y408226D01*
Y417239D01*
X267400Y423739D01*
Y427431D01*
X273694Y442627D01*
Y449771D01*
X275138Y451215D01*
G01X164800Y263300D02*
X165000D01*
X165059Y263359D01*
X165660D01*
X166737Y264436D01*
Y264946D01*
X175691Y273900D01*
X179196D01*
X181891Y276595D01*
X186679Y278579D01*
X187418Y279318D01*
Y281405D01*
X188352Y282339D01*
X188657Y282465D01*
X189216D01*
X195452Y285050D01*
X198025D01*
X204533Y291558D01*
X206031D01*
X221140Y306667D01*
Y313733D01*
X231137Y323730D01*
X232837D01*
X236660Y327553D01*
Y331382D01*
X237500Y333417D01*
X241354Y337271D01*
Y339251D01*
X242034Y339931D01*
Y356892D01*
X258240Y373098D01*
Y395157D01*
X266850Y403767D01*
Y406847D01*
X267700Y407697D01*
Y411939D01*
X275540Y419779D01*
Y422815D01*
X278000Y425275D01*
Y428199D01*
X276196Y430003D01*
X273496D01*
X272999Y430500D01*
G01X274619Y424725D02*
X274414D01*
X265160Y415471D01*
Y406458D01*
X256290Y397588D01*
Y373157D01*
X240614Y357481D01*
Y343623D01*
X234807Y337816D01*
X230625D01*
X226423Y333614D01*
Y328083D01*
X223800Y325460D01*
Y319100D01*
X219500Y314800D01*
Y310280D01*
X215220Y306000D01*
X212200D01*
X210700Y304500D01*
Y298236D01*
X205442Y292978D01*
X203944D01*
X199040Y288074D01*
X188927Y283885D01*
X188205D01*
X187665Y283661D01*
X185998Y281994D01*
Y279907D01*
X181147Y277898D01*
X178749Y275500D01*
X174900D01*
X168682Y269282D01*
X167618D01*
X165800Y271100D01*
Y272300D01*
X168656Y275156D01*
G01X161400Y307600D02*
Y309900D01*
X158600Y312700D01*
Y315500D01*
X168900Y325800D01*
X175158D01*
X179798Y330440D01*
X181800D01*
X187450Y336090D01*
X192121D01*
X192700Y336669D01*
Y343601D01*
X195828Y346729D01*
Y353031D01*
X191408Y357451D01*
G01X184645Y175496D02*
X183135Y173986D01*
Y168571D01*
X184019Y167687D01*
X185412D01*
X186284Y166815D01*
Y165421D01*
X187168Y164537D01*
X188562D01*
X189304Y163795D01*
Y159000D01*
X190800Y157504D01*
Y150000D01*
X187100Y146300D01*
X172100D01*
G01X187794Y156599D02*
X189400Y154993D01*
Y151100D01*
X186700Y148400D01*
X171640D01*
X170290Y147050D01*
Y145550D01*
X175340Y140500D01*
X176000D01*
G01X189700Y140400D02*
X187600Y138300D01*
X175300D01*
X168700Y144900D01*
Y147800D01*
X170620Y149720D01*
X183052D01*
X186155Y152823D01*
Y163745D01*
X185363Y164537D01*
X184019D01*
X183135Y165421D01*
Y166765D01*
X182343Y167557D01*
X177443D01*
X176800Y168200D01*
Y175835D01*
X173059Y179576D01*
Y181842D01*
X169129Y185772D01*
X167620Y189414D01*
Y204875D01*
X167950Y205205D01*
Y206705D01*
X167700Y206955D01*
Y208573D01*
X168171Y209044D01*
Y209911D01*
X172210Y213950D01*
Y217810D01*
X174200Y219800D01*
Y222440D01*
X171990Y224650D01*
Y227843D01*
X170980Y228853D01*
Y251021D01*
X169802Y252199D01*
Y255225D01*
X171183Y256607D01*
X171200Y256624D01*
Y257600D01*
X171700Y258100D01*
X178623D01*
X179708Y257015D01*
X181815D01*
X182700Y257900D01*
X190901D01*
X199780Y266779D01*
Y270346D01*
X201854Y272420D01*
X207699D01*
X212730Y277451D01*
X223652D01*
X227641Y281440D01*
X229970D01*
X231265Y282735D01*
Y286265D01*
X236500Y291500D01*
Y295498D01*
X243832Y302830D01*
X251262D01*
X252790Y304358D01*
Y318844D01*
X249790Y321844D01*
Y324129D01*
X250116Y324916D01*
X250258Y325258D01*
X252994Y327994D01*
Y351076D01*
X269450Y367532D01*
Y382917D01*
X276088Y389555D01*
X276850Y391394D01*
Y395734D01*
X286680Y405564D01*
Y410547D01*
X287500Y411367D01*
Y416100D01*
G01X170800Y193100D02*
X173100Y187548D01*
Y186400D01*
X177788Y181712D01*
X178787D01*
X180251Y180248D01*
X188452D01*
X189434Y179266D01*
Y177666D01*
X190094Y177006D01*
X191570D01*
X192454Y176122D01*
Y175446D01*
X196100Y171800D01*
X203391D01*
X205140Y170051D01*
Y168174D01*
X205713Y167601D01*
X235799D01*
X236511Y166889D01*
Y165289D01*
X237392Y164408D01*
X238776D01*
X242817Y160367D01*
Y158783D01*
X243491Y158109D01*
X246291D01*
X249720Y154680D01*
X255944D01*
X257100Y153524D01*
Y148200D01*
X256600Y147700D01*
Y145340D01*
X258040Y143900D01*
G01X174400Y251936D02*
X172300Y249836D01*
Y229400D01*
X175600Y226100D01*
Y220500D01*
X176200Y219900D01*
Y216970D01*
X173530Y214300D01*
Y213403D01*
X170178Y210051D01*
Y203177D01*
X170126Y203051D01*
Y197591D01*
X168940Y196405D01*
Y190860D01*
X171200Y188600D01*
Y186400D01*
X179900Y177700D01*
Y170792D01*
X181495Y169197D01*
G01X263768Y163369D02*
X255462Y171675D01*
Y176068D01*
X254524Y177006D01*
X254420Y177049D01*
X250152D01*
X249200Y178001D01*
Y179400D01*
X248315Y180285D01*
X246973D01*
X246000Y181258D01*
Y182400D01*
X245032Y183368D01*
X218335D01*
X213759Y187944D01*
X207768D01*
X205127Y190585D01*
Y192077D01*
X202201Y195003D01*
X196688D01*
X195746Y195945D01*
X179907D01*
X178346Y197506D01*
G01Y191244D02*
X181931Y194829D01*
X194465D01*
X195210Y194084D01*
X200137D01*
X201949Y192272D01*
Y190413D01*
X205724Y186638D01*
X213523D01*
X218139Y182022D01*
X221354D01*
X223150Y180226D01*
X229854D01*
X231396Y181768D01*
X242132D01*
X243744Y180156D01*
X245130D01*
X246000Y179286D01*
Y177900D01*
X246800Y177100D01*
X248500D01*
X249200Y176400D01*
Y174800D01*
X250100Y173900D01*
X251500D01*
X252300Y173100D01*
Y171275D01*
X252800Y170775D01*
X254992D01*
X259039Y166728D01*
Y165698D01*
X260034Y164703D01*
G01X181495Y191244D02*
X183964Y193713D01*
X193849D01*
X194677Y192885D01*
X198108D01*
X198832Y192161D01*
Y190561D01*
X204293Y185100D01*
X207378D01*
X209100Y183378D01*
X214180D01*
X216846Y180712D01*
X219743D01*
X220833Y179622D01*
Y177887D01*
X221630Y177090D01*
X232601D01*
X233424Y177913D01*
Y179748D01*
X234283Y180607D01*
X241593D01*
X242810Y179390D01*
Y178020D01*
X242800Y178010D01*
Y178000D01*
X243700Y177100D01*
X245400D01*
X246000Y176500D01*
Y174900D01*
X247000Y173900D01*
X248500D01*
X249200Y173200D01*
Y171700D01*
X250063Y170837D01*
X251245D01*
X252259Y169823D01*
Y168541D01*
X253178Y167622D01*
X255578D01*
X256614Y166586D01*
Y164215D01*
X257195Y163634D01*
X258070D01*
X260058Y161646D01*
G01X261220Y149581D02*
Y153280D01*
X256300Y158200D01*
X255600D01*
X249263Y164537D01*
X246973D01*
X238510Y173000D01*
X219300D01*
X218500Y172200D01*
X209733D01*
X207947Y173986D01*
X199213D01*
X198753Y174446D01*
Y176122D01*
X197869Y177006D01*
X196193D01*
X195100Y178099D01*
Y179775D01*
X191570Y183305D01*
X190295D01*
X189400Y184200D01*
Y185699D01*
X188599Y186500D01*
X177700D01*
X175846Y188354D01*
Y193426D01*
X175196Y194076D01*
Y197506D01*
G01X174336Y192800D02*
Y186764D01*
X177700Y183400D01*
X188500D01*
X189434Y182466D01*
Y181169D01*
X190318Y180285D01*
X191615D01*
X194000Y177900D01*
Y176099D01*
X197199Y172900D01*
X205797D01*
X207917Y170780D01*
X218780D01*
X219900Y171900D01*
X237800D01*
X242900Y166800D01*
Y165400D01*
X251300Y157000D01*
X255944D01*
X259910Y153034D01*
Y148403D01*
X260446Y147867D01*
G01X170400Y214700D02*
X170590Y214890D01*
Y227376D01*
X169660Y228306D01*
Y250474D01*
X168300Y251834D01*
Y257299D01*
X170421Y259420D01*
X176625D01*
X177840Y260635D01*
X180874D01*
X183133Y259700D01*
X187360D01*
X190833Y263173D01*
X193972D01*
X198460Y267661D01*
Y270893D01*
X201307Y273740D01*
X207152D01*
X212183Y278771D01*
X219171D01*
X224680Y284280D01*
X228190D01*
X229220Y283250D01*
G01X174292Y263300D02*
Y263420D01*
X176247Y265375D01*
X178375D01*
X179710Y266710D01*
X187010D01*
X189000Y268700D01*
Y272790D01*
X191317Y275107D01*
X197835D01*
X202738Y280010D01*
X206473D01*
X212800Y286337D01*
Y288477D01*
X225400Y301077D01*
Y311963D01*
X231885Y318448D01*
X235087D01*
X242479Y325840D01*
X244029Y329581D01*
X245614Y331166D01*
Y337484D01*
X246294Y338164D01*
Y354701D01*
X262500Y370907D01*
Y386406D01*
X268190Y392096D01*
Y398060D01*
X271790Y401660D01*
Y405720D01*
X274190Y408120D01*
Y408900D01*
G01X171592Y263312D02*
Y265060D01*
X174007Y267475D01*
X177474D01*
X178809Y268810D01*
X185810D01*
X186900Y269900D01*
Y272700D01*
X194210Y280010D01*
X198630D01*
X202250Y283630D01*
X202730D01*
X203400Y284300D01*
X206500D01*
X207234Y285034D01*
Y285996D01*
X206396Y286834D01*
Y287796D01*
X207075Y288475D01*
X208037D01*
X208875Y287637D01*
X209837D01*
X210516Y288316D01*
Y289278D01*
X209678Y290116D01*
Y291078D01*
X210357Y291757D01*
X211319D01*
X212157Y290919D01*
X213119D01*
X216320Y294120D01*
Y295082D01*
X215432Y295970D01*
Y296932D01*
X216111Y297611D01*
X217073D01*
X217961Y296723D01*
X218923D01*
X219602Y297402D01*
Y298364D01*
X218714Y299252D01*
Y300214D01*
X219393Y300893D01*
X220355D01*
X221243Y300005D01*
X222205D01*
X223980Y301780D01*
Y312552D01*
X231296Y319868D01*
X233537D01*
X239500Y325831D01*
Y330817D01*
X239911Y331810D01*
X244194Y336093D01*
Y338073D01*
X244874Y338753D01*
Y355290D01*
X261080Y371496D01*
Y393979D01*
X269690Y402589D01*
Y405669D01*
X272200Y408179D01*
Y412421D01*
X278900Y419121D01*
Y421400D01*
G01X168710Y272256D02*
X169086Y272632D01*
X169532D01*
X170500Y273600D01*
Y277651D01*
X172508Y279659D01*
X175859D01*
X179810Y283610D01*
X185605D01*
X187050Y285055D01*
X187653Y285305D01*
X188615D01*
X198254Y289297D01*
X203355Y294398D01*
X204853D01*
X209280Y298825D01*
Y308381D01*
X215199Y314300D01*
X216991D01*
X222380Y319689D01*
Y326049D01*
X225003Y328672D01*
Y334203D01*
X230036Y339236D01*
X234218D01*
X239194Y344212D01*
Y358494D01*
X254870Y374170D01*
Y398177D01*
X263740Y407047D01*
Y416060D01*
X271887Y424207D01*
Y427262D01*
X272307Y427682D01*
X275100D01*
G01X186200Y125600D02*
X189672Y129072D01*
Y136772D01*
X194000Y141100D01*
Y153340D01*
X192500Y154840D01*
Y163700D01*
X191792Y164408D01*
X190446D01*
X189434Y165421D01*
Y166666D01*
X188413Y167687D01*
X187168D01*
X186284Y168571D01*
Y170837D01*
X187794Y172347D01*
G01X190944Y166047D02*
X192577Y167680D01*
X198020D01*
X198810Y166890D01*
Y158770D01*
X199370Y158210D01*
X223100D01*
X224000Y157310D01*
Y144801D01*
X235390Y133411D01*
Y128689D01*
X234882Y128181D01*
X233860Y127760D01*
X232910Y126810D01*
Y124850D01*
X232500Y124440D01*
Y116500D01*
X235080Y113920D01*
Y109737D01*
X232500Y107157D01*
Y103615D01*
X235382Y100733D01*
X236642D01*
X236648Y100739D01*
G01X261126Y155574D02*
X255441Y161259D01*
X254541D01*
X245093Y170707D01*
X243593D01*
X242810Y171490D01*
Y172973D01*
X241883Y173900D01*
X218881D01*
X218181Y173200D01*
X213543D01*
X211922Y174821D01*
Y176300D01*
X211171Y177051D01*
X200974D01*
X191505Y186520D01*
X190280D01*
X188705Y188095D01*
X184645D01*
G01X187794Y169197D02*
X189397Y170800D01*
X201200D01*
X202032Y169968D01*
Y168571D01*
X203046Y167557D01*
X204168D01*
X205182Y166543D01*
Y165421D01*
X206066Y164537D01*
X235498D01*
X236511Y163524D01*
Y158743D01*
X237075Y158179D01*
X239218D01*
X239848Y157549D01*
Y155496D01*
X250845Y144499D01*
Y144062D01*
X256436Y138471D01*
X259626D01*
X263240Y134857D01*
Y129727D01*
X266625Y126342D01*
Y120726D01*
X276331Y111020D01*
X280259D01*
X295090Y96189D01*
Y93250D01*
X297510Y90830D01*
X312390D01*
X316200Y94640D01*
Y96000D01*
X318700Y98500D01*
X321160D01*
X329360Y106700D01*
X333200D01*
X342100Y97800D01*
X346600D01*
X349100Y100300D01*
Y314400D01*
X347842Y315658D01*
X342499D01*
X337120Y321037D01*
Y353720D01*
X341400Y358000D01*
Y381635D01*
X336105Y386930D01*
X333643D01*
X326825Y393748D01*
X321639D01*
X320720Y392829D01*
X314234D01*
X308926Y398137D01*
Y401900D01*
G01X184645Y191244D02*
X186205Y192804D01*
X192664D01*
X201568Y183900D01*
X207100D01*
X208300Y182700D01*
Y180715D01*
X208800Y180215D01*
X215456D01*
X219471Y176200D01*
X233466D01*
X234340Y177074D01*
X242026D01*
X242900Y176200D01*
Y174900D01*
X243900Y173900D01*
X245400D01*
X246000Y173300D01*
Y171500D01*
X246700Y170800D01*
X248400D01*
X249200Y170000D01*
Y168100D01*
X249700Y167600D01*
X251500D01*
X252300Y166800D01*
Y165336D01*
X253100Y164536D01*
X254464D01*
X261719Y157281D01*
G01X246700Y454100D02*
Y456233D01*
X243629Y459304D01*
X234169D01*
X233225Y458360D01*
X231445D01*
X224847Y455626D01*
X210959D01*
X208333Y453000D01*
X198533D01*
X190580Y445047D01*
Y439753D01*
X193020Y437313D01*
Y425140D01*
X190370Y422490D01*
G01X246700Y451500D02*
X244700Y453500D01*
Y455980D01*
X242696Y457984D01*
X234716D01*
X233772Y457040D01*
X231715D01*
X225117Y454306D01*
X211506D01*
X208880Y451680D01*
X199080D01*
X191900Y444500D01*
Y440300D01*
X194340Y437860D01*
Y435848D01*
X195210Y434978D01*
Y434977D01*
X197110Y433077D01*
Y431577D01*
X195000Y429467D01*
Y422540D01*
G01X292700Y403700D02*
X286683D01*
X278170Y395187D01*
Y391074D01*
X277195Y388721D01*
X270770Y382296D01*
Y366985D01*
X254314Y350529D01*
Y327447D01*
X251377Y324510D01*
X251110Y323866D01*
Y322411D01*
X251377Y322144D01*
Y322124D01*
X254110Y319391D01*
Y303810D01*
X251810Y301510D01*
X244380D01*
X238000Y295130D01*
Y291133D01*
X232585Y285718D01*
Y282188D01*
X230517Y280120D01*
X228188D01*
X224199Y276131D01*
X213513D01*
X208482Y271100D01*
X202401D01*
X201100Y269799D01*
Y265120D01*
G01X240200Y450650D02*
X238550D01*
X237500Y449600D01*
Y447617D01*
X230503Y440620D01*
X227852D01*
X205032Y417800D01*
Y414105D01*
X206150Y412987D01*
Y412821D01*
G01X199940Y423700D02*
X200700Y424460D01*
Y441091D01*
X202155Y444604D01*
Y446255D01*
X205300Y449400D01*
X207053D01*
X215712Y452986D01*
X225381D01*
X231980Y455720D01*
X234319D01*
X235263Y456664D01*
X236517D01*
X238031Y455150D01*
Y452831D01*
X236800Y451600D01*
X235400D01*
G01X205223Y422665D02*
X206980Y424422D01*
Y433352D01*
X206600Y433732D01*
Y436476D01*
X210234Y440110D01*
X223542D01*
X226852Y443420D01*
X227670D01*
X231250Y447000D01*
G01X222402Y156599D02*
Y142788D01*
X227230Y137960D01*
Y128630D01*
X225300Y126700D01*
Y125200D01*
G01X258500Y146400D02*
Y153284D01*
X255884Y155900D01*
X250840D01*
X239053Y167687D01*
X237524D01*
X236640Y168571D01*
Y170261D01*
X236101Y170800D01*
X227155D01*
X225552Y169197D01*
G01X239900Y117550D02*
Y116502D01*
X241476Y114926D01*
Y112503D01*
X242510Y111469D01*
Y105478D01*
X241457Y104425D01*
Y101876D01*
X242856Y100477D01*
Y99036D01*
X239660Y95840D01*
Y91920D01*
G01X231851Y162898D02*
X230341Y161388D01*
Y155973D01*
X230830Y155484D01*
Y150591D01*
X230253Y150014D01*
Y144149D01*
X239350Y135052D01*
Y125650D01*
X245790Y119210D01*
X247950D01*
X249010Y118150D01*
Y113690D01*
X253900Y108800D01*
X259400D01*
X261569Y106631D01*
Y99169D01*
X261000Y98600D01*
X260970D01*
G01X259894Y90072D02*
X258322Y91644D01*
Y94518D01*
X259382Y95578D01*
X261077D01*
X262889Y97390D01*
Y107178D01*
X259947Y110120D01*
X254447D01*
X250330Y114237D01*
Y118697D01*
X248497Y120530D01*
X246337D01*
X240670Y126197D01*
Y135599D01*
X232384Y143885D01*
Y148884D01*
G01X238150Y156599D02*
Y147608D01*
X244005Y141753D01*
Y141227D01*
X250564Y134668D01*
Y128827D01*
X257550Y121841D01*
Y118777D01*
X269523Y106804D01*
Y104304D01*
X273580Y100247D01*
Y97220D01*
X275781Y95019D01*
X278300D01*
G01X231851Y156599D02*
Y153095D01*
X234194Y150752D01*
Y143942D01*
X240263Y137873D01*
X243623D01*
X247924Y133572D01*
Y127732D01*
X254910Y120746D01*
Y117683D01*
X265801Y106792D01*
Y106040D01*
G01X231851Y159748D02*
X233399Y158200D01*
Y156065D01*
X234505Y154959D01*
X235627D01*
X236511Y154075D01*
Y143492D01*
X240810Y139193D01*
X244171D01*
X249244Y134120D01*
Y128279D01*
X256230Y121293D01*
Y118230D01*
X268203Y106257D01*
Y103757D01*
X272260Y99700D01*
Y96500D01*
X276400Y92360D01*
Y92300D01*
G01X238150Y159748D02*
X238831D01*
X242066Y156513D01*
Y155562D01*
X244751Y152877D01*
X251354D01*
G01X234500Y293500D02*
Y296332D01*
X240600Y302432D01*
Y308033D01*
X247157Y314590D01*
X248673D01*
X249733Y315650D01*
Y320034D01*
X248470Y321297D01*
Y324392D01*
X248896Y325422D01*
X249139Y326006D01*
X251674Y328541D01*
Y351623D01*
X268130Y368079D01*
Y383464D01*
X274905Y390239D01*
X275530Y391748D01*
Y396281D01*
X285360Y406111D01*
Y411094D01*
X285600Y411334D01*
Y416760D01*
X286680Y417840D01*
Y440925D01*
X289654Y443899D01*
Y448770D01*
X291703Y450819D01*
G01X238400Y304200D02*
Y307700D01*
X245520Y314820D01*
Y317860D01*
X245790Y318130D01*
Y324879D01*
X246814Y327350D01*
X246818Y327359D01*
X246940Y327654D01*
X249034Y329748D01*
Y353525D01*
X265490Y369981D01*
Y384559D01*
X272400Y391469D01*
Y392400D01*
G01X261100Y443500D02*
X259890Y442290D01*
Y432190D01*
X254640Y426940D01*
Y409861D01*
X244200Y399421D01*
Y389583D01*
X233600Y378983D01*
Y377300D01*
G01X276660Y316900D02*
Y286571D01*
X281431Y281800D01*
X286900D01*
X291200Y277500D01*
X304800D01*
X308100Y274200D01*
Y264700D01*
X299800Y256400D01*
X265600D01*
X261500Y252300D01*
Y247200D01*
X259500Y245200D01*
Y231500D01*
X258600Y230600D01*
X250000D01*
X247637Y228237D01*
Y225852D01*
G01X335475Y358500D02*
X331520Y362455D01*
Y376372D01*
X329000Y378892D01*
Y382199D01*
X327610Y383589D01*
Y384899D01*
X326199Y386310D01*
X325719D01*
X322240Y389789D01*
X312611D01*
X302608Y399792D01*
X287076D01*
X281300Y394016D01*
Y390244D01*
X280000Y387105D01*
Y378667D01*
X279607Y378274D01*
Y366506D01*
X272945Y359844D01*
X272898Y359805D01*
X272850Y359800D01*
X267996D01*
X262600Y354404D01*
Y336300D01*
X263970Y334930D01*
X264005Y334887D01*
X264010Y334839D01*
Y332752D01*
X264005Y332704D01*
X263966Y332657D01*
X255730Y324421D01*
Y314271D01*
X256900Y313100D01*
X257900Y312100D01*
G01X243010Y323400D02*
X244260Y324650D01*
X245810Y328391D01*
X247700Y330281D01*
Y330282D01*
X247714Y330296D01*
Y336784D01*
X247700Y336798D01*
Y337561D01*
X247714Y337575D01*
Y354112D01*
X264170Y370568D01*
Y385106D01*
X270290Y391226D01*
Y397190D01*
X273890Y400790D01*
Y404850D01*
X276390Y407350D01*
Y411270D01*
X277700Y412580D01*
G01X247923Y319000D02*
X247150Y319773D01*
Y324655D01*
X247676Y325928D01*
X248020Y326755D01*
X250354Y329089D01*
Y352978D01*
X266810Y369434D01*
Y384011D01*
X273777Y390978D01*
X274210Y392023D01*
Y397910D01*
X278630Y402330D01*
Y405170D01*
X277700Y406100D01*
G01X335500Y380000D02*
X336810Y381310D01*
Y384216D01*
X335516Y385510D01*
X333054D01*
X326236Y392328D01*
X322228D01*
X321309Y391409D01*
X313645D01*
X306716Y398338D01*
Y405235D01*
X306251Y405700D01*
X305451D01*
X304786Y405035D01*
Y401977D01*
X304221Y401412D01*
X303421D01*
X302856Y401977D01*
Y404335D01*
X302291Y404900D01*
X301491D01*
X300926Y404335D01*
Y401977D01*
X300361Y401412D01*
X299561D01*
X298996Y401977D01*
Y404335D01*
X298431Y404900D01*
X297631D01*
X297066Y404335D01*
Y401977D01*
X296501Y401412D01*
X286404D01*
X279590Y394598D01*
Y390731D01*
X278380Y387809D01*
Y380080D01*
X276447Y378147D01*
X274521D01*
X272190Y375816D01*
Y366396D01*
X257100Y351306D01*
Y339760D01*
X258410Y338450D01*
Y329393D01*
X253320Y324303D01*
Y323327D01*
G01X269700Y411379D02*
Y411930D01*
X276960Y419190D01*
Y422110D01*
X280380Y425530D01*
Y435754D01*
X276632Y439502D01*
G01X267100Y432900D02*
X269500Y437977D01*
Y447630D01*
X271710Y449840D01*
G01X266727Y443185D02*
X268080Y441832D01*
Y440280D01*
X263800Y436000D01*
Y430300D01*
G01X285250Y117250D02*
X290690Y111810D01*
Y107209D01*
X297892Y100007D01*
X313907D01*
X322236Y108336D01*
X325048D01*
X331212Y114500D01*
X342728D01*
X344720Y116492D01*
Y219243D01*
X341678Y222285D01*
X314415D01*
X311891Y224809D01*
Y240538D01*
X309677Y242752D01*
Y275689D01*
X302879Y282487D01*
G01X287755Y287538D02*
X285069Y284852D01*
X282113D01*
X279300Y287665D01*
Y313400D01*
X280100Y314200D01*
Y345869D01*
X277500Y348469D01*
G01X302800Y286200D02*
X300100D01*
X294384Y280484D01*
X290083D01*
X287325Y283242D01*
X281856D01*
X277980Y287118D01*
Y314679D01*
X278780Y315479D01*
Y321160D01*
X273000Y326940D01*
Y329646D01*
X273355Y330001D01*
G01X277572Y351198D02*
Y351957D01*
X280900Y355285D01*
Y362699D01*
X281227Y363026D01*
Y377602D01*
X281700Y378075D01*
Y386478D01*
X283000Y389617D01*
Y392347D01*
X283500Y392847D01*
X290145D01*
X292498Y395200D01*
X304600D01*
X311631Y388169D01*
X316369D01*
X326338Y378200D01*
X327400D01*
X329900Y375700D01*
Y360100D01*
X336100Y353900D01*
Y320614D01*
X343014Y313700D01*
X347100D01*
G01X342200Y100500D02*
X344200D01*
X348080Y104380D01*
Y307191D01*
X334800Y320471D01*
Y342943D01*
X323090Y354653D01*
Y379553D01*
X315941Y386702D01*
X311641D01*
X310223Y388120D01*
X297123D01*
X294624Y390619D01*
X290698D01*
X290017Y391300D01*
X285651D01*
X285191Y390840D01*
G01X283715Y452769D02*
X285633D01*
X287400Y451002D01*
Y444270D01*
X284580Y441450D01*
Y418710D01*
X283500Y417630D01*
Y415000D01*
X282890Y414390D01*
X276178D01*
X274190Y412402D01*
Y408900D01*
G01X278900Y421400D02*
X280300D01*
X282480Y423580D01*
Y442359D01*
X285600Y445479D01*
Y448049D01*
X283674Y449975D01*
G01X298840Y279640D02*
Y282140D01*
X300997Y284297D01*
X303629D01*
X310997Y276929D01*
Y243299D01*
X313211Y241085D01*
Y225356D01*
X314962Y223605D01*
X342225D01*
X346040Y219790D01*
Y114660D01*
X342080Y110700D01*
X329279D01*
X325595Y107016D01*
X322783D01*
X320500Y104733D01*
Y100400D01*
G01X287630Y389378D02*
X290477D01*
X290698Y389599D01*
X294201D01*
X296700Y387100D01*
X309800D01*
X310700Y386200D01*
Y386102D01*
X311120Y385682D01*
X315518D01*
X322070Y379130D01*
Y354230D01*
X333780Y342520D01*
Y320048D01*
X347060Y306768D01*
Y113603D01*
X342180Y108723D01*
Y106900D01*
M02*
